G04 ================== begin FILE IDENTIFICATION RECORD ==================*
G04 Layout Name:  12432-1.brd*
G04 Film Name:    L7GND*
G04 File Format:  Gerber RS274X*
G04 File Origin:  Cadence Allegro 16.2-S037*
G04 Origin Date:  Wed Oct 17 11:00:13 2012*
G04 *
G04 Layer:  VIA CLASS/L7GND*
G04 Layer:  PIN/L7GND*
G04 Layer:  ETCH/L7GND*
G04 Layer:  DRAWING FORMAT/LAYER_PCB_STORY*
G04 Layer:  DRAWING FORMAT/LAYER_L7GND*
G04 *
G04 Offset:    (0.00 0.00)*
G04 Mirror:    No*
G04 Mode:      Negative*
G04 Rotation:  0*
G04 FullContactRelief:  No*
G04 UndefLineWidth:     6.00*
G04 ================== end FILE IDENTIFICATION RECORD ====================*
%FSLAX35Y35*MOIN*%
%IR0*IPPOS*OFA0.00000B0.00000*MIA0B0*SFA1.00000B1.00000*%
%AMMACRO19*
4,1,16,.07873,.05044,
.086293,.036002,
.091233,.020471,
.093402,.004317,
.092733,-.011967,
.089246,-.027888,
.083047,-.042962,
.07873,-.05044,
.08234,-.05406,
.090476,-.038941,
.095864,-.022638,
.098339,-.005647,
.097825,.011515,
.094339,.028327,
.087987,.044279,
.08234,.05406,
.07873,.05044,
0.0*
4,1,16,.05044,-.07873,
.036002,-.086293,
.020471,-.091233,
.004317,-.093402,
-.011967,-.092733,
-.027888,-.089246,
-.042962,-.083047,
-.05044,-.07873,
-.05406,-.08234,
-.038941,-.090476,
-.022638,-.095864,
-.005647,-.098339,
.011515,-.097825,
.028327,-.094339,
.044279,-.087987,
.05406,-.08234,
.05044,-.07873,
0.0*
4,1,16,-.07873,-.05044,
-.086293,-.036002,
-.091233,-.020471,
-.093402,-.004317,
-.092733,.011967,
-.089246,.027888,
-.083047,.042962,
-.07873,.05044,
-.08234,.05406,
-.090476,.038941,
-.095864,.022638,
-.098339,.005647,
-.097825,-.011515,
-.094339,-.028327,
-.087987,-.044279,
-.08234,-.05406,
-.07873,-.05044,
0.0*
4,1,16,-.05044,.07873,
-.036002,.086293,
-.020471,.091233,
-.004317,.093402,
.011967,.092733,
.027888,.089246,
.042962,.083047,
.05044,.07873,
.05406,.08234,
.038941,.090476,
.022638,.095864,
.005647,.098339,
-.011515,.097825,
-.028327,.094339,
-.044279,.087987,
-.05406,.08234,
-.05044,.07873,
0.0*
%
%ADD19MACRO19*%
%ADD15C,.032*%
%AMMACRO21*
4,1,20,-.01,-.05608,
-.015853,-.053819,
-.021224,-.050576,
-.025951,-.046449,
-.029889,-.041565,
-.032919,-.03607,
-.034949,-.030133,
-.035918,-.023934,
-.036,-.0215,
-.036,-.015,
-.031,-.015,
-.031,-.0215,
-.030529,-.026882,
-.029131,-.032101,
-.026847,-.036998,
-.023748,-.041424,
-.019928,-.045244,
-.015502,-.048343,
-.010605,-.050627,
-.01,-.05084,
-.01,-.05608,
90.*
4,1,20,.01,-.05608,
.01,-.05084,
.014943,-.048658,
.019432,-.045652,
.023331,-.041911,
.026521,-.03755,
.028905,-.032702,
.030411,-.027513,
.030993,-.022142,
.031,-.0215,
.031,-.015,
.036,-.015,
.036,-.0215,
.035453,-.027751,
.033829,-.033811,
.031177,-.039498,
.027579,-.044638,
.023142,-.049074,
.018002,-.052673,
.012316,-.055325,
.01,-.05608,
90.*
4,1,20,-.036,.015,
-.036,.0215,
-.035453,.027751,
-.033829,.033811,
-.031177,.039498,
-.027579,.044638,
-.023142,.049074,
-.018002,.052673,
-.012316,.055325,
-.01,.05608,
-.01,.05084,
-.014943,.048658,
-.019432,.045652,
-.023331,.041911,
-.026521,.03755,
-.028905,.032702,
-.030411,.027513,
-.030993,.022142,
-.031,.0215,
-.031,.015,
-.036,.015,
90.*
4,1,20,.031,.015,
.031,.0215,
.030529,.026882,
.029131,.032101,
.026847,.036998,
.023748,.041424,
.019928,.045244,
.015502,.048343,
.010605,.050627,
.01,.05084,
.01,.05608,
.015853,.053819,
.021224,.050576,
.025951,.046449,
.029889,.041565,
.032919,.03607,
.034949,.030133,
.035918,.023934,
.036,.0215,
.036,.015,
.031,.015,
90.*
%
%ADD21MACRO21*%
%ADD16C,.036*%
%AMMACRO22*
4,1,15,.00398,.00044,
.003999,.000208,
.004004,-.000025,
.003996,-.000258,
.00398,-.00044,
.00483,-.00129,
.004897,-.001007,
.004947,-.000721,
.004981,-.000432,
.004997,-.000141,
.004997,.000149,
.00498,.00044,
.004946,.000729,
.004895,.001015,
.00483,.00129,
.00398,.00044,
90.*
4,1,15,.00044,-.00398,
.000208,-.003999,
-.000025,-.004004,
-.000258,-.003996,
-.00044,-.00398,
-.00129,-.00483,
-.001007,-.004897,
-.000721,-.004947,
-.000432,-.004981,
-.000141,-.004997,
.000149,-.004997,
.00044,-.00498,
.000729,-.004946,
.001015,-.004895,
.00129,-.00483,
.00044,-.00398,
90.*
4,1,15,-.00398,-.00044,
-.003999,-.000208,
-.004004,.000025,
-.003996,.000258,
-.00398,.00044,
-.00483,.00129,
-.004897,.001007,
-.004947,.000721,
-.004981,.000432,
-.004997,.000141,
-.004997,-.000149,
-.00498,-.00044,
-.004946,-.000729,
-.004895,-.001015,
-.00483,-.00129,
-.00398,-.00044,
90.*
4,1,15,-.00044,.00398,
-.000208,.003999,
.000025,.004004,
.000258,.003996,
.00044,.00398,
.00129,.00483,
.001007,.004897,
.000721,.004947,
.000432,.004981,
.000141,.004997,
-.000149,.004997,
-.00044,.00498,
-.000729,.004946,
-.001015,.004895,
-.00129,.00483,
-.00044,.00398,
90.*
%
%ADD22MACRO22*%
%AMMACRO11*
4,1,15,.00398,.00044,
.003999,.000208,
.004004,-.000025,
.003996,-.000258,
.00398,-.00044,
.00483,-.00129,
.004897,-.001007,
.004947,-.000721,
.004981,-.000432,
.004997,-.000141,
.004997,.000149,
.00498,.00044,
.004946,.000729,
.004895,.001015,
.00483,.00129,
.00398,.00044,
0.0*
4,1,15,.00044,-.00398,
.000208,-.003999,
-.000025,-.004004,
-.000258,-.003996,
-.00044,-.00398,
-.00129,-.00483,
-.001007,-.004897,
-.000721,-.004947,
-.000432,-.004981,
-.000141,-.004997,
.000149,-.004997,
.00044,-.00498,
.000729,-.004946,
.001015,-.004895,
.00129,-.00483,
.00044,-.00398,
0.0*
4,1,15,-.00398,-.00044,
-.003999,-.000208,
-.004004,.000025,
-.003996,.000258,
-.00398,.00044,
-.00483,.00129,
-.004897,.001007,
-.004947,.000721,
-.004981,.000432,
-.004997,.000141,
-.004997,-.000149,
-.00498,-.00044,
-.004946,-.000729,
-.004895,-.001015,
-.00483,-.00129,
-.00398,-.00044,
0.0*
4,1,15,-.00044,.00398,
-.000208,.003999,
.000025,.004004,
.000258,.003996,
.00044,.00398,
.00129,.00483,
.001007,.004897,
.000721,.004947,
.000432,.004981,
.000141,.004997,
-.000149,.004997,
-.00044,.00498,
-.000729,.004946,
-.001015,.004895,
-.00129,.00483,
-.00044,.00398,
0.0*
%
%ADD11MACRO11*%
%ADD18C,.101*%
%ADD10C,.114*%
%AMMACRO17*
4,1,20,-.01,-.05608,
-.015853,-.053819,
-.021224,-.050576,
-.025951,-.046449,
-.029889,-.041565,
-.032919,-.03607,
-.034949,-.030133,
-.035918,-.023934,
-.036,-.0215,
-.036,-.015,
-.031,-.015,
-.031,-.0215,
-.030529,-.026882,
-.029131,-.032101,
-.026847,-.036998,
-.023748,-.041424,
-.019928,-.045244,
-.015502,-.048343,
-.010605,-.050627,
-.01,-.05084,
-.01,-.05608,
270.*
4,1,20,.01,-.05608,
.01,-.05084,
.014943,-.048658,
.019432,-.045652,
.023331,-.041911,
.026521,-.03755,
.028905,-.032702,
.030411,-.027513,
.030993,-.022142,
.031,-.0215,
.031,-.015,
.036,-.015,
.036,-.0215,
.035453,-.027751,
.033829,-.033811,
.031177,-.039498,
.027579,-.044638,
.023142,-.049074,
.018002,-.052673,
.012316,-.055325,
.01,-.05608,
270.*
4,1,20,-.036,.015,
-.036,.0215,
-.035453,.027751,
-.033829,.033811,
-.031177,.039498,
-.027579,.044638,
-.023142,.049074,
-.018002,.052673,
-.012316,.055325,
-.01,.05608,
-.01,.05084,
-.014943,.048658,
-.019432,.045652,
-.023331,.041911,
-.026521,.03755,
-.028905,.032702,
-.030411,.027513,
-.030993,.022142,
-.031,.0215,
-.031,.015,
-.036,.015,
270.*
4,1,20,.031,.015,
.031,.0215,
.030529,.026882,
.029131,.032101,
.026847,.036998,
.023748,.041424,
.019928,.045244,
.015502,.048343,
.010605,.050627,
.01,.05084,
.01,.05608,
.015853,.053819,
.021224,.050576,
.025951,.046449,
.029889,.041565,
.032919,.03607,
.034949,.030133,
.035918,.023934,
.036,.0215,
.036,.015,
.031,.015,
270.*
%
%ADD17MACRO17*%
%ADD14C,.119*%
%ADD23C,.174*%
%AMMACRO20*
4,1,15,.00398,.00044,
.003999,.000208,
.004004,-.000025,
.003996,-.000258,
.00398,-.00044,
.00483,-.00129,
.004897,-.001007,
.004947,-.000721,
.004981,-.000432,
.004997,-.000141,
.004997,.000149,
.00498,.00044,
.004946,.000729,
.004895,.001015,
.00483,.00129,
.00398,.00044,
180.*
4,1,15,.00044,-.00398,
.000208,-.003999,
-.000025,-.004004,
-.000258,-.003996,
-.00044,-.00398,
-.00129,-.00483,
-.001007,-.004897,
-.000721,-.004947,
-.000432,-.004981,
-.000141,-.004997,
.000149,-.004997,
.00044,-.00498,
.000729,-.004946,
.001015,-.004895,
.00129,-.00483,
.00044,-.00398,
180.*
4,1,15,-.00398,-.00044,
-.003999,-.000208,
-.004004,.000025,
-.003996,.000258,
-.00398,.00044,
-.00483,.00129,
-.004897,.001007,
-.004947,.000721,
-.004981,.000432,
-.004997,.000141,
-.004997,-.000149,
-.00498,-.00044,
-.004946,-.000729,
-.004895,-.001015,
-.00483,-.00129,
-.00398,-.00044,
180.*
4,1,15,-.00044,.00398,
-.000208,.003999,
.000025,.004004,
.000258,.003996,
.00044,.00398,
.00129,.00483,
.001007,.004897,
.000721,.004947,
.000432,.004981,
.000141,.004997,
-.000149,.004997,
-.00044,.00498,
-.000729,.004946,
-.001015,.004895,
-.00129,.00483,
-.00044,.00398,
180.*
%
%ADD20MACRO20*%
%AMMACRO12*
4,1,15,.00398,.00044,
.003999,.000208,
.004004,-.000025,
.003996,-.000258,
.00398,-.00044,
.00483,-.00129,
.004897,-.001007,
.004947,-.000721,
.004981,-.000432,
.004997,-.000141,
.004997,.000149,
.00498,.00044,
.004946,.000729,
.004895,.001015,
.00483,.00129,
.00398,.00044,
270.*
4,1,15,.00044,-.00398,
.000208,-.003999,
-.000025,-.004004,
-.000258,-.003996,
-.00044,-.00398,
-.00129,-.00483,
-.001007,-.004897,
-.000721,-.004947,
-.000432,-.004981,
-.000141,-.004997,
.000149,-.004997,
.00044,-.00498,
.000729,-.004946,
.001015,-.004895,
.00129,-.00483,
.00044,-.00398,
270.*
4,1,15,-.00398,-.00044,
-.003999,-.000208,
-.004004,.000025,
-.003996,.000258,
-.00398,.00044,
-.00483,.00129,
-.004897,.001007,
-.004947,.000721,
-.004981,.000432,
-.004997,.000141,
-.004997,-.000149,
-.00498,-.00044,
-.004946,-.000729,
-.004895,-.001015,
-.00483,-.00129,
-.00398,-.00044,
270.*
4,1,15,-.00044,.00398,
-.000208,.003999,
.000025,.004004,
.000258,.003996,
.00044,.00398,
.00129,.00483,
.001007,.004897,
.000721,.004947,
.000432,.004981,
.000141,.004997,
-.000149,.004997,
-.00044,.00498,
-.000729,.004946,
-.001015,.004895,
-.00129,.00483,
-.00044,.00398,
270.*
%
%ADD12MACRO12*%
%AMMACRO13*
4,1,16,.07256,.04427,
.079145,.030998,
.083325,.016783,
.084974,.002059,
.08404,-.012728,
.080553,-.027128,
.074619,-.040704,
.07256,-.04427,
.07619,-.04791,
.083352,-.033952,
.087981,-.018962,
.089937,-.003396,
.089161,.012273,
.085675,.027569,
.079586,.042027,
.07619,.04791,
.07256,.04427,
0.0*
4,1,16,.04427,-.07256,
.030998,-.079145,
.016783,-.083325,
.002059,-.084974,
-.012728,-.08404,
-.027128,-.080553,
-.040704,-.074619,
-.04427,-.07256,
-.04791,-.07619,
-.033952,-.083352,
-.018962,-.087981,
-.003396,-.089937,
.012273,-.089161,
.027569,-.085675,
.042027,-.079586,
.04791,-.07619,
.04427,-.07256,
0.0*
4,1,16,-.07256,-.04427,
-.079145,-.030998,
-.083325,-.016783,
-.084974,-.002059,
-.08404,.012728,
-.080553,.027128,
-.074619,.040704,
-.07256,.04427,
-.07619,.04791,
-.083352,.033952,
-.087981,.018962,
-.089937,.003396,
-.089161,-.012273,
-.085675,-.027569,
-.079586,-.042027,
-.07619,-.04791,
-.07256,-.04427,
0.0*
4,1,16,-.04427,.07256,
-.030998,.079145,
-.016783,.083325,
-.002059,.084974,
.012728,.08404,
.027128,.080553,
.040704,.074619,
.04427,.07256,
.04791,.07619,
.033952,.083352,
.018962,.087981,
.003396,.089937,
-.012273,.089161,
-.027569,.085675,
-.042027,.079586,
-.04791,.07619,
-.04427,.07256,
0.0*
%
%ADD13MACRO13*%
%ADD24C,.02*%
%ADD25C,.006*%
%ADD29R,.142X.028*%
%ADD27C,.09706*%
%ADD26C,.11506*%
%ADD28C,.17006*%
G75*
%LPD*%
G75*
G36*
G01X-6000Y-6000D02*
X1039465D01*
Y1998126D01*
X-6000D01*
Y-6000D01*
G37*
%LPC*%
G75*
G36*
G01X1030461Y1686599D02*
X1028283Y1684421D01*
X1023228D01*
G03X1016287Y1677480I0J-6941D01*
G01Y1621265D01*
X1014109Y1619087D01*
X989744D01*
G03Y1608866I0J-5110D01*
G01X1014109D01*
X1016287Y1606688D01*
Y1432756D01*
G03X1023228Y1425815I6941J0D01*
G01X1028283D01*
X1030461Y1423637D01*
Y3937D01*
G02X1029528Y3004I-933J0D01*
G01X3937D01*
G02X3004Y3937I0J933D01*
G01Y408401D01*
X5182Y410579D01*
X5468D01*
Y410016D01*
X19668D01*
Y410579D01*
X19882D01*
G03Y424067I0J6744D01*
G01X5182D01*
X3004Y426245D01*
Y817849D01*
X5182Y820027D01*
X19882D01*
G03Y833516I0J6745D01*
G01X5182D01*
X3004Y835694D01*
Y1392653D01*
X5182Y1394831D01*
X5468D01*
Y1394268D01*
X19668D01*
Y1394831D01*
X19882D01*
G03Y1408319I0J6744D01*
G01X5182D01*
X3004Y1410497D01*
Y1802101D01*
X5182Y1804279D01*
X19882D01*
G03Y1817768I0J6744D01*
G01X5182D01*
X3004Y1819946D01*
Y1988189D01*
G02X3937Y1989122I933J0D01*
G01X1029528D01*
G02X1030461Y1988189I0J-933D01*
G01Y1686599D01*
G37*
%LPD*%
G75*
G54D29*
X12568Y375983D03*
Y379920D03*
Y391731D03*
Y395668D03*
Y407479D03*
Y431103D03*
Y435040D03*
Y446851D03*
Y450788D03*
Y462599D03*
Y466536D03*
Y478347D03*
Y482284D03*
Y494095D03*
Y498032D03*
Y509843D03*
Y513780D03*
Y525591D03*
Y529528D03*
Y580709D03*
Y584646D03*
Y612205D03*
Y616142D03*
Y627953D03*
Y631890D03*
Y643701D03*
Y647638D03*
Y659449D03*
Y663386D03*
Y675197D03*
Y679134D03*
Y1360235D03*
Y1364172D03*
Y1375983D03*
Y1379920D03*
Y1391731D03*
Y1415355D03*
Y1419292D03*
Y1431103D03*
Y1435040D03*
Y1446851D03*
Y1450788D03*
Y1462599D03*
Y1466536D03*
Y1478347D03*
Y1482284D03*
Y1494095D03*
Y1498032D03*
Y1509843D03*
Y1513780D03*
Y1564961D03*
Y1568898D03*
Y1596457D03*
Y1600394D03*
Y1612205D03*
Y1616142D03*
Y1627953D03*
Y1631890D03*
Y1643701D03*
Y1647638D03*
Y1659449D03*
Y1663386D03*
G54D27*
X78150Y28858D03*
Y178464D03*
Y434370D03*
Y583976D03*
Y839882D03*
Y989488D03*
Y1245394D03*
Y1395000D03*
Y1650906D03*
Y1800512D03*
X158071Y191614D03*
Y341220D03*
Y597126D03*
Y746732D03*
Y1002638D03*
Y1152244D03*
Y1408150D03*
Y1557756D03*
Y1813662D03*
Y1963268D03*
X886417Y191614D03*
Y341220D03*
Y597126D03*
Y746732D03*
Y1002638D03*
Y1152244D03*
Y1408150D03*
Y1557756D03*
Y1813662D03*
Y1963268D03*
G54D26*
X9843Y353144D03*
Y717711D03*
Y762617D03*
Y875216D03*
Y1337396D03*
Y1701963D03*
Y1746869D03*
Y1859468D03*
G54D28*
X1019291Y1416024D03*
Y1694212D03*
G54D19*
X129921Y17716D03*
X994093Y1889751D03*
G54D15*
X14999Y1936050D03*
X8499Y1937550D03*
X15099Y1944050D03*
X5303Y1947050D03*
X11703Y1951946D03*
X17499Y1961050D03*
X26299Y383854D03*
Y387629D03*
X28100Y374000D03*
X26299Y399601D03*
Y403376D03*
X35900Y412600D03*
X26524Y426720D03*
X26399Y423322D03*
X28900Y417800D03*
X26492Y439350D03*
X26599Y442749D03*
X26899Y454850D03*
X26799Y458497D03*
X26486Y462648D03*
X26499Y466250D03*
X26299Y478404D03*
X26515Y481798D03*
X36499Y517775D03*
X26399Y501966D03*
Y505741D03*
X36499Y521550D03*
X26599Y525648D03*
Y529302D03*
X27199Y539600D03*
X39217Y554750D03*
X33307Y557938D03*
X26199Y547176D03*
X29999Y557150D03*
X33699Y561850D03*
X36499Y566350D03*
X28000Y578500D03*
X25581Y567763D03*
X27699Y573750D03*
X28808Y593150D03*
X28700Y596549D03*
X27499Y620203D03*
Y623857D03*
X37999Y611550D03*
X26800Y611500D03*
X32200Y603710D03*
X31598Y607102D03*
X39600Y626984D03*
X38300Y633800D03*
X26568Y635950D03*
Y639604D03*
X26737Y651957D03*
X26999Y656550D03*
X27687Y667447D03*
Y671101D03*
X27700Y682700D03*
X27299Y783550D03*
X35300Y789375D03*
X32800Y803050D03*
X37416Y799033D03*
X37099Y811350D03*
X35559Y795112D03*
X31699Y814350D03*
X37216Y807951D03*
X39649Y822000D03*
X29299Y836901D03*
X40400Y840792D03*
X29600Y854000D03*
X23299Y863050D03*
X26662Y861550D03*
X25000Y858100D03*
X20999Y1320550D03*
Y1352050D03*
X25000Y1357742D03*
X25507Y1372045D03*
X25558Y1368447D03*
X28499Y1391050D03*
X32333Y1389383D03*
X30500Y1395500D03*
X32451Y1411468D03*
X28999Y1411550D03*
X32094Y1448448D03*
X28697Y1448296D03*
X33206Y1432352D03*
X30499Y1434550D03*
X30378Y1462518D03*
X33915Y1462681D03*
X34465Y1481683D03*
X30999Y1482050D03*
X34099Y1497550D03*
X30499D03*
X30115Y1511900D03*
X33512Y1512051D03*
X29631Y1533063D03*
X31999Y1517846D03*
Y1521500D03*
X37999Y1530900D03*
X24199Y1523700D03*
X38500Y1534600D03*
X32099Y1535550D03*
X26705Y1534795D03*
X30199Y1545450D03*
X36340Y1558809D03*
X34896Y1555730D03*
X38208Y1569841D03*
X25521Y1563350D03*
X30520Y1572049D03*
X27123Y1572205D03*
X39000Y1573500D03*
X34999Y1595350D03*
X28899Y1613524D03*
X32299D03*
X33599Y1600200D03*
X29499Y1630050D03*
X32663Y1628181D03*
X31999Y1661127D03*
X28600Y1661039D03*
X29626Y1645002D03*
X33026Y1645051D03*
X32700Y1673300D03*
X32494Y1669706D03*
X29100Y1669500D03*
X30500Y1697500D03*
X39900Y1751200D03*
X41200Y1747050D03*
X30274Y1787238D03*
X35675Y1783450D03*
X39324Y1780623D03*
X38094Y1785840D03*
X38878Y1799571D03*
X34599Y1805123D03*
X37699Y1789850D03*
X37574Y1794050D03*
X31811Y1790271D03*
X40478Y1795820D03*
X32099Y1797150D03*
X28550Y1828153D03*
X29899Y1821050D03*
X34099Y1822850D03*
X35876Y1812350D03*
X34129Y1815267D03*
X36532Y1825352D03*
X36399Y1828750D03*
X26099Y1824950D03*
X29599Y1844350D03*
X28123Y1831527D03*
X25999Y1842550D03*
X39699Y1833850D03*
X23030Y1922038D03*
X26765Y1921945D03*
X25499Y1956050D03*
X32999Y1960555D03*
X31799Y1979050D03*
X45800Y405200D03*
X61400Y452600D03*
X62497Y474346D03*
X60003Y534150D03*
X59999Y537550D03*
X42867Y548450D03*
X43099Y555850D03*
X46299Y552950D03*
X49799Y559150D03*
X42599Y567850D03*
X42202Y608195D03*
X41400Y611500D03*
X47626Y611300D03*
X45701Y607700D03*
X42709Y625607D03*
X41500Y642800D03*
X47101Y632355D03*
X41500Y635000D03*
X52500D03*
X48999Y642900D03*
X50410Y695801D03*
X50300Y699200D03*
X45100Y793100D03*
X44046Y799554D03*
X46887Y803413D03*
X51100Y806300D03*
X49900Y813200D03*
X56281Y801350D03*
X50399Y836250D03*
X46700Y820100D03*
X54074Y815750D03*
X62405Y820300D03*
X46576Y832951D03*
X48346Y844529D03*
X58699Y837250D03*
X44697Y1546793D03*
X44299Y1550950D03*
X42199Y1601050D03*
X45877Y1728477D03*
Y1724823D03*
X47000Y1737100D03*
X43600D03*
X42275Y1754000D03*
X45799Y1757650D03*
X47440Y1761391D03*
X47400Y1765250D03*
X43751Y1780559D03*
X46999Y1779550D03*
X46199Y1783050D03*
X43925Y1767890D03*
X47604Y1769005D03*
X45782Y1771877D03*
X47499Y1775350D03*
X47899Y1798650D03*
X48049Y1791450D03*
X42199Y1792250D03*
X46799Y1794900D03*
X61009Y1822340D03*
X46499Y1836550D03*
X47166Y1839884D03*
X43099Y1833850D03*
X57999Y1891050D03*
X42499Y1902550D03*
X48499Y1897050D03*
X50499Y1961550D03*
X43462Y1961160D03*
X78700Y74200D03*
Y70700D03*
X74999Y70550D03*
Y74050D03*
X74499Y80650D03*
Y84050D03*
X65999Y216050D03*
X65000Y455500D03*
X62503Y470946D03*
X62978Y486217D03*
X63067Y489616D03*
X65599Y514250D03*
X68000Y546500D03*
X72500Y545000D03*
X81251Y607249D03*
Y619251D03*
X82499Y627050D03*
X80499Y664550D03*
X76999D03*
X65500Y817700D03*
X80500Y817000D03*
X76540Y850938D03*
X75500Y847700D03*
X68860Y838706D03*
X69499Y842950D03*
X63499Y843050D03*
X74220Y854150D03*
X72362Y849550D03*
X80699Y1004450D03*
Y1000450D03*
X72000Y1013400D03*
X63273Y1023974D03*
X66499Y1025050D03*
X75500Y1012261D03*
X65486Y1031515D03*
X76999Y1196550D03*
X77758Y1357742D03*
X76000Y1431100D03*
X80043Y1544691D03*
X78600Y1561900D03*
X75000Y1561800D03*
X74400Y1574800D03*
X80400Y1571766D03*
X82329Y1568117D03*
X79000Y1555500D03*
X82429D03*
X74800Y1584700D03*
X74500Y1692000D03*
X74400Y1778100D03*
X80099Y1817250D03*
X80999Y1836550D03*
X97499Y90050D03*
X86899Y130567D03*
X86599Y126750D03*
X95350Y204550D03*
X89800Y208550D03*
X95500Y513400D03*
X98900D03*
X86199Y536025D03*
Y532250D03*
X89000Y816500D03*
X90000Y826000D03*
X90500Y831500D03*
X98700Y822550D03*
X98000Y833500D03*
X98700Y842600D03*
X94999Y901550D03*
X85999Y940429D03*
X86399Y937050D03*
X102100Y968500D03*
X99000Y965000D03*
X104600Y980500D03*
X90000Y993100D03*
X92600Y996100D03*
X88000Y1008500D03*
X101499Y1072550D03*
X103999Y1216863D03*
X102900Y1196050D03*
X103686Y1223863D03*
X101541Y1262607D03*
X101399Y1292550D03*
X102700Y1321363D03*
X86890Y1342860D03*
Y1346635D03*
X102350Y1344500D03*
Y1348154D03*
X97229Y1373337D03*
X97000Y1377600D03*
X98599Y1491350D03*
X100699Y1471050D03*
X83932Y1544705D03*
X100800Y1536450D03*
X96200Y1550100D03*
X99899Y1539850D03*
X100000Y1546650D03*
X90324Y1538800D03*
X97499Y1554550D03*
X98144Y1534309D03*
X96999Y1558050D03*
X89373Y1561073D03*
X85600Y1561500D03*
X95499Y1665418D03*
X93999Y1703050D03*
X85341Y1752245D03*
X85194Y1748848D03*
X99199Y1761899D03*
X99999Y1753575D03*
X101399Y1784700D03*
X85599Y1797350D03*
X96600Y1826000D03*
X86649Y1817100D03*
X90000Y1827900D03*
X93500D03*
X97999Y1843050D03*
X115876Y125973D03*
Y130050D03*
X122397Y252688D03*
X122799Y249150D03*
X107499Y497050D03*
X109400Y543200D03*
X106000D03*
X105100Y600000D03*
X107000Y604800D03*
X125499Y635550D03*
Y638950D03*
X110500Y790200D03*
X111100Y813400D03*
X111200Y799450D03*
X111207Y810001D03*
X110700Y795700D03*
X111089Y806603D03*
X110800Y803100D03*
X110499Y834550D03*
X108845Y931657D03*
X109099Y928250D03*
X108200Y963600D03*
X107300Y986000D03*
X107400Y992900D03*
X123999Y1054050D03*
Y1050650D03*
X116700Y1063500D03*
X112699Y1058974D03*
X105499Y1080550D03*
X106718Y1076050D03*
X105999Y1085800D03*
X105600Y1069500D03*
X124423Y1077523D03*
Y1081177D03*
X120749Y1093990D03*
X125900Y1091282D03*
X123999Y1102550D03*
X108999Y1102050D03*
X106999Y1194550D03*
X106162Y1205702D03*
X123970Y1221573D03*
X119399Y1298113D03*
X116999Y1288050D03*
X120507Y1317050D03*
X107999Y1307713D03*
X116499Y1328013D03*
X120507Y1328096D03*
X109228Y1337090D03*
Y1333315D03*
X119499Y1339050D03*
X112440Y1358196D03*
X112999Y1361550D03*
X121000Y1364000D03*
X113500Y1344500D03*
Y1348154D03*
X125100Y1366000D03*
X117390Y1426201D03*
Y1429976D03*
X104935Y1440634D03*
X104999Y1444941D03*
X124290Y1469241D03*
X123808Y1465050D03*
X106999Y1454450D03*
X118499Y1694050D03*
X117499Y1706050D03*
X109499Y1712213D03*
X112753Y1716613D03*
X122642Y1704243D03*
X112562Y1720613D03*
X123749Y1711550D03*
X109499Y1743550D03*
X109399Y1739550D03*
X110099Y1759875D03*
X123393Y1870859D03*
X123592Y1874254D03*
X141499Y427550D03*
Y423050D03*
X135499Y517550D03*
X137899Y545451D03*
X138416Y553500D03*
X140940Y561800D03*
X141300Y565900D03*
X127999Y645550D03*
X131400Y644600D03*
X144238Y645356D03*
Y649131D03*
X137481Y1077557D03*
X137477Y1081177D03*
X132499Y1094550D03*
X138600Y1124600D03*
X135850Y1322250D03*
X143700Y1332500D03*
X140000Y1332600D03*
X129000Y1356500D03*
X142999Y1456373D03*
X142900Y1460000D03*
X133090Y1699959D03*
X128749Y1703300D03*
X131999Y1710050D03*
X135499Y1710150D03*
X141999Y1764550D03*
X137999Y1861497D03*
Y1865151D03*
X154200Y168500D03*
X149400Y166400D03*
X149999Y243504D03*
Y239729D03*
X159600Y446399D03*
X163549Y517100D03*
X152000Y520813D03*
X149000Y537500D03*
X150500Y545000D03*
X150750Y540416D03*
X156500Y554000D03*
X157000Y573851D03*
X160824Y577000D03*
X165499Y815550D03*
X153500Y834600D03*
X154799Y838050D03*
X153499Y918550D03*
X163500Y937100D03*
X152500Y960000D03*
X154749Y979149D03*
Y968249D03*
X164700Y1085400D03*
X147400Y1321600D03*
X148024Y1333525D03*
X157400Y1596550D03*
X160200Y1598500D03*
X152633Y1677967D03*
X150999Y1713550D03*
X165900Y1790500D03*
X161900Y1793400D03*
X174999Y79050D03*
X175499Y86572D03*
X176399Y94872D03*
X178999Y79050D03*
X186999Y99050D03*
X188999Y120800D03*
X173500Y166315D03*
X187699Y492850D03*
X172499Y491053D03*
X176799Y493850D03*
X188000Y484500D03*
X171722Y513827D03*
X183499Y556100D03*
X169106Y815865D03*
X172500Y919294D03*
X172000Y931600D03*
X171100Y935000D03*
X171000Y939500D03*
X172000Y961000D03*
X170250Y948500D03*
X179499Y1275550D03*
X181000Y1365500D03*
X180500Y1369900D03*
X171999Y1662250D03*
X169600Y1682300D03*
X169100Y1685800D03*
X174250Y1694500D03*
X181100Y1682700D03*
X177900Y1690400D03*
X205499Y105550D03*
X207999Y109550D03*
X199900Y554050D03*
X200799Y896600D03*
X199149Y1362900D03*
X194700Y1385700D03*
X201499Y1781050D03*
X225499Y68550D03*
X230749Y76300D03*
X213499Y104650D03*
X223499Y108150D03*
X218499Y190550D03*
X225298Y281114D03*
X220000Y516400D03*
X211750Y894600D03*
X221800Y1069300D03*
X229800Y1073600D03*
X226800Y1093400D03*
X224750Y1483950D03*
X229025Y1471576D03*
X227814Y1887513D03*
X223436Y1890465D03*
X229800Y1875700D03*
X218100Y1886400D03*
X214999Y1909550D03*
X213138Y1952703D03*
X210999Y1942050D03*
X233749Y110800D03*
X237899Y107050D03*
X247800Y269700D03*
X250300Y275100D03*
X250400Y283100D03*
X239600Y278600D03*
X246800Y677100D03*
X249700Y682500D03*
X238500Y680800D03*
X249800Y689900D03*
X233500Y1066100D03*
X242000Y1066000D03*
X247500Y1085500D03*
X251500Y1136700D03*
X241000Y1469600D03*
X233700Y1481600D03*
X231800Y1887100D03*
X231999Y1914050D03*
X249600Y1896800D03*
X249499Y1928050D03*
X253871Y291410D03*
X254499Y697700D03*
X269500Y1135500D03*
X261999Y1516050D03*
X257499Y1911050D03*
X264499Y1964050D03*
X282800Y87500D03*
X293999Y293550D03*
X284999Y338650D03*
X281499Y338550D03*
X279939Y728610D03*
X285499Y745050D03*
X282099D03*
X282500Y1135000D03*
X295000Y1513000D03*
X283499Y1556050D03*
X279999D03*
X285499Y1930050D03*
X288709Y1948042D03*
X284999Y1947691D03*
X308999Y87050D03*
X297499Y97550D03*
X315800Y100500D03*
X301249Y346050D03*
X310999Y757050D03*
X310249Y1569800D03*
X310499Y1957050D03*
X324800Y89400D03*
X323400Y105200D03*
X326499Y334054D03*
Y337454D03*
X327999Y740550D03*
X327749Y744050D03*
X329499Y801550D03*
X330540Y795509D03*
X320499Y798050D03*
X326500Y1550200D03*
X330300Y1561200D03*
X331622Y1944767D03*
X332103Y1948133D03*
X343499Y31650D03*
X354999Y72050D03*
X341499Y63050D03*
Y67110D03*
X344520Y406329D03*
X350499Y597300D03*
Y715050D03*
X340699Y1046086D03*
X345499Y1096550D03*
X345424Y1310050D03*
X347324Y1524000D03*
X354500Y1559500D03*
X349774Y1582900D03*
X354000Y1584900D03*
X353499Y1710450D03*
X348499Y1762050D03*
X342999Y1947409D03*
X342621Y1943409D03*
X358999Y61550D03*
X365499Y86550D03*
X371999Y549300D03*
X375999Y698550D03*
X371500Y880600D03*
X364499Y1099050D03*
X372999Y1123550D03*
X370149Y1320050D03*
X366149Y1554050D03*
X377900Y1703800D03*
X381999Y53550D03*
X394199Y45050D03*
X381999Y57050D03*
X400499Y406329D03*
X394649Y630600D03*
X390999Y1514398D03*
Y1517798D03*
X385499Y1735050D03*
X402499Y1476850D03*
X400999Y1575550D03*
X645549Y1815134D03*
X644360Y1819137D03*
X707600Y1815600D03*
X711652Y1822109D03*
X711848Y1825504D03*
X732549Y1806634D03*
X733149Y1798634D03*
X733049Y1814134D03*
X757499Y1079550D03*
X757999Y1484050D03*
X758499Y1893550D03*
X772499Y323050D03*
X772873Y326924D03*
X780499Y330050D03*
X771105Y722789D03*
X769999Y733050D03*
X771999Y1124550D03*
X772499Y1130050D03*
X779499Y1131050D03*
X774542Y1530050D03*
X774577Y1533796D03*
X771499Y1936550D03*
Y1940050D03*
X791499Y333050D03*
X789999Y336550D03*
X781999Y725550D03*
X788999Y736050D03*
X791999Y733050D03*
X792154Y1135926D03*
X789499Y1138050D03*
X784499Y1529050D03*
X791499Y1543550D03*
X793999Y1541050D03*
X793000Y1803500D03*
X795849Y1805500D03*
X802499Y1951550D03*
X800431Y1941193D03*
X792499Y1949050D03*
X794499Y1941050D03*
X782999Y1937050D03*
X802099Y1961950D03*
X809940Y264940D03*
X822100Y261700D03*
Y279500D03*
X816700Y274300D03*
X820600Y664300D03*
X808660Y667540D03*
X813200Y675900D03*
X807000Y1072900D03*
X815400Y1078800D03*
X803199Y1151850D03*
X822100Y1466800D03*
X809960Y1478040D03*
X814700Y1486300D03*
X804899Y1556950D03*
X807000Y1822300D03*
X803500Y1822708D03*
X822700Y1871100D03*
X810900Y1882440D03*
X805900Y1887560D03*
X829917Y216200D03*
X833576Y215432D03*
X837999Y219550D03*
X842499Y280924D03*
X827500Y274500D03*
X829800Y666650D03*
X825700Y1083100D03*
X825800Y1072300D03*
X827700Y1487600D03*
X828500Y1877800D03*
X834799Y1946950D03*
X854400Y264600D03*
X847878Y250040D03*
X851278Y249974D03*
X865499Y288050D03*
X851172Y655432D03*
X847772Y655370D03*
X852696Y671197D03*
X850833Y1061441D03*
X847233Y1061492D03*
X852333Y1077716D03*
X864499Y1128750D03*
X861849Y1376050D03*
X848888Y1466402D03*
X852288Y1466346D03*
X854327Y1477550D03*
X863699Y1501250D03*
X862800Y1712700D03*
X853499Y1871036D03*
X850099Y1871056D03*
X854814Y1883550D03*
X863699Y1906450D03*
X857099Y1917650D03*
X867500Y163924D03*
X867576Y159924D03*
X878078Y240103D03*
Y243878D03*
X868799Y294750D03*
X867899Y321550D03*
X868299Y336150D03*
X879750Y570550D03*
X879950Y565050D03*
X878596Y645573D03*
Y649348D03*
X883083Y979183D03*
X879708Y971892D03*
X878233Y1051095D03*
X877964Y1054485D03*
X866700Y1379796D03*
X866596Y1375796D03*
X878054Y1456450D03*
X877853Y1459991D03*
X867523Y1542821D03*
X867199Y1535150D03*
X886439Y1717600D03*
X873800Y1733600D03*
X879700Y1786300D03*
X879664Y1782213D03*
X866914Y1861840D03*
Y1865615D03*
X901499Y92050D03*
X897555Y90494D03*
X902499Y110550D03*
X898999D03*
X907499Y131800D03*
X902999Y556050D03*
X900499Y962100D03*
X900999Y979050D03*
X889800Y1711500D03*
X926999Y115050D03*
Y122050D03*
X910999Y124550D03*
X916499Y172550D03*
X917499Y1796550D03*
X943499Y82550D03*
X930999Y115550D03*
X938499D03*
X937999Y122050D03*
X934499Y118750D03*
X961499Y93350D03*
X965150Y1639500D03*
X961702Y1636102D03*
X969600Y1638300D03*
X967600Y1651100D03*
X971558Y1646500D03*
X986400Y1639302D03*
X987100Y1624900D03*
X981200Y1625800D03*
X977500Y1660500D03*
X981500Y1653000D03*
X980800Y1659600D03*
X982050Y1649302D03*
X978000Y1668000D03*
X974000Y1670700D03*
X984211Y1667500D03*
G54D21*
X167323Y179803D03*
Y353031D03*
Y585315D03*
Y758543D03*
Y990827D03*
Y1164055D03*
Y1396339D03*
Y1569567D03*
Y1801851D03*
Y1975079D03*
X895669Y179803D03*
Y353031D03*
Y585315D03*
Y758543D03*
Y990827D03*
Y1164055D03*
Y1396339D03*
Y1569567D03*
Y1801851D03*
Y1975079D03*
G54D16*
X36999Y725050D03*
Y719550D03*
X37499Y714050D03*
X41499Y719550D03*
X36499Y740050D03*
Y732550D03*
X43499Y657550D03*
X50999Y720050D03*
X46499Y719550D03*
X51499Y724550D03*
X46499D03*
X41999D03*
X46499Y730550D03*
X41999Y735050D03*
Y731050D03*
X46499Y735050D03*
X41999Y739550D03*
X46499Y739050D03*
X51999Y767050D03*
X47999Y767550D03*
X52499Y771550D03*
X47999D03*
X47499Y1915050D03*
Y1930550D03*
X62499Y1939550D03*
X58999Y1958050D03*
X67000Y1011500D03*
X81499Y1589050D03*
X83499Y1594050D03*
X78999Y1593550D03*
X74999D03*
X74499Y1602050D03*
Y1598050D03*
X83499D03*
Y1602050D03*
X78999Y1598050D03*
Y1602050D03*
Y1891550D03*
X82999D03*
Y1887550D03*
X78999D03*
X62999Y1914550D03*
X78999Y1896050D03*
X78433Y1900010D03*
X78999Y1904050D03*
X83499Y1896050D03*
X83433Y1904010D03*
X62999Y1926050D03*
X81499Y1915550D03*
X82499Y1957050D03*
X73499D03*
X66499D03*
X73499Y1945550D03*
X96999Y49550D03*
X92999Y52050D03*
X97800Y36000D03*
X96900Y40400D03*
X93000Y44900D03*
X92900Y39700D03*
X97999Y199050D03*
X93500Y445300D03*
X97699Y449850D03*
X93199D03*
X97999Y445550D03*
X94500Y456800D03*
X100500Y456700D03*
X98999Y488050D03*
X94499Y486550D03*
X93499Y477050D03*
X97699Y481550D03*
Y477050D03*
X93499Y481550D03*
X98001Y856950D03*
X97800Y851800D03*
X93808Y852063D03*
X94001Y856895D03*
X97499Y862050D03*
X93299D03*
X93900Y882400D03*
X97900D03*
X97700Y887400D03*
X93690Y887139D03*
X97499Y892550D03*
X93499Y892050D03*
X100999Y1101050D03*
X104999D03*
X100999Y1096550D03*
X97300Y1564100D03*
X92499Y1589050D03*
X86999D03*
X83999Y1900050D03*
Y1945050D03*
X98433Y1940510D03*
X98999Y1944550D03*
X102433Y1940555D03*
X103433Y1944510D03*
X92499Y1959050D03*
X116400Y56000D03*
X114800Y68500D03*
X105006Y1096866D03*
X110999Y1130550D03*
X115200Y1130300D03*
X110999Y1126050D03*
Y1122050D03*
Y1118050D03*
X114999Y1126050D03*
Y1122050D03*
Y1118050D03*
X123500Y1360300D03*
X122600Y1565000D03*
X105749Y1712749D03*
X124433Y1908510D03*
X124999Y1912550D03*
X119999Y1978550D03*
X119499Y1972550D03*
X129100Y55900D03*
X127499Y65050D03*
X141999Y65550D03*
X129999Y78050D03*
X127999Y99550D03*
Y425050D03*
Y421050D03*
Y429550D03*
X135999Y472550D03*
X135140Y478930D03*
X145649Y509550D03*
X136349Y509050D03*
X140499Y499050D03*
X136299D03*
X147300Y526700D03*
X144149Y1230113D03*
Y1226113D03*
Y1222113D03*
X129100Y1564700D03*
X127200Y1569800D03*
X130499Y1730050D03*
X128000Y1735000D03*
X144499Y1729550D03*
X139500Y1730500D03*
X133000Y1734500D03*
X129999Y1908550D03*
X129433Y1912510D03*
X127499Y1978550D03*
X133499D03*
X132999Y1972550D03*
X126999D03*
X167499Y43550D03*
X156499Y66050D03*
X166999Y88050D03*
X166499Y83550D03*
Y79050D03*
X158499D03*
Y84050D03*
Y88550D03*
Y93550D03*
X166999Y92550D03*
X165499Y106050D03*
X166999Y97050D03*
X155999Y181050D03*
X149700Y471600D03*
X154100Y476500D03*
X164600Y476700D03*
X153499Y502550D03*
X148999D03*
X147590Y521500D03*
X161999Y768050D03*
X152499Y810550D03*
Y816050D03*
Y820550D03*
Y825050D03*
X156499Y870550D03*
Y876050D03*
X163999Y863050D03*
X159999D03*
X155999Y859050D03*
Y863050D03*
X159459Y896616D03*
X163499Y896550D03*
X155499Y891050D03*
Y896050D03*
X157499Y904550D03*
Y909050D03*
X151999Y936550D03*
X152499Y931550D03*
X159186Y946117D03*
X151300Y1049300D03*
X148499Y1222113D03*
Y1226113D03*
X148486Y1230113D03*
X167499Y1714113D03*
X162499D03*
X165499Y1730613D03*
X167999Y1726613D03*
X163499D03*
X189499Y39150D03*
X183499Y45550D03*
X169999Y103050D03*
X179999Y442550D03*
X179649Y438550D03*
X183999D03*
Y442550D03*
Y447050D03*
X179999D03*
X171300Y476700D03*
X187499Y531613D03*
Y536113D03*
X188999Y541113D03*
Y549613D03*
Y545613D03*
X175823Y1297070D03*
X179999Y1301550D03*
Y1292550D03*
X175499D03*
X179999Y1296613D03*
X175499Y1302113D03*
X179999Y1306050D03*
X175499Y1306113D03*
X180299Y1626550D03*
X180000Y1619600D03*
X180299Y1634550D03*
X179733Y1630590D03*
X172499Y1714050D03*
X170499Y1731050D03*
X172499Y1726613D03*
X197999Y39900D03*
X193999D03*
X208499Y45650D03*
X199999Y46050D03*
X194499Y44050D03*
X192499Y57550D03*
X194999Y490050D03*
X190499Y487550D03*
X191199Y491550D03*
X193499Y541113D03*
Y549613D03*
X193999Y545550D03*
X204496Y846111D03*
X204649Y838050D03*
X208999D03*
X209000Y846113D03*
X204649Y842113D03*
X208986D03*
X195700Y1619100D03*
X195600Y1623700D03*
X225499Y52550D03*
Y46550D03*
Y63550D03*
Y58050D03*
X227999Y178050D03*
X227499Y192050D03*
X227999Y187050D03*
Y182550D03*
X215999Y887550D03*
X220499D03*
X215499Y883550D03*
X219499Y939613D03*
X214999D03*
X219499Y926613D03*
X214999D03*
X219499Y948613D03*
Y943813D03*
X214999Y944113D03*
Y948613D03*
X226999Y1941050D03*
X231999Y178050D03*
Y192050D03*
Y187050D03*
Y182550D03*
X267498Y305114D03*
Y300114D03*
Y295114D03*
Y310114D03*
X268499Y701550D03*
Y706550D03*
Y716550D03*
Y711550D03*
X272499Y1153050D03*
X268499D03*
X263999D03*
X259999Y1152992D03*
X271999Y1161550D03*
X267999D03*
X263499D03*
X259499D03*
X260999Y1503550D03*
X266999Y1512550D03*
X267349Y1518150D03*
Y1522550D03*
Y1527172D03*
X266999Y1915550D03*
Y1920050D03*
Y1924550D03*
Y1929050D03*
Y1933550D03*
X294100Y28000D03*
X289499Y39050D03*
X286603Y34928D03*
X289999Y72550D03*
X290999Y67550D03*
X288499Y76550D03*
X289499Y80550D03*
X279998Y304114D03*
Y299614D03*
Y295114D03*
Y308614D03*
X293998Y361114D03*
Y356614D03*
Y352114D03*
X289998Y361114D03*
Y356614D03*
Y352114D03*
X280999Y701550D03*
Y705550D03*
Y717550D03*
X280433Y713590D03*
X294999Y767050D03*
X290999D03*
X294999Y762550D03*
Y758050D03*
X290999Y762550D03*
Y758050D03*
X279499Y1510550D03*
Y1515050D03*
X279075Y1525957D03*
X278567Y1529925D03*
X293998Y1573614D03*
Y1569114D03*
X289998Y1573614D03*
Y1569114D03*
X293998Y1578114D03*
X289998D03*
X293999Y1933050D03*
X281999Y1918550D03*
Y1923550D03*
Y1928550D03*
X293999Y1971050D03*
Y1966550D03*
Y1962050D03*
X289499Y1961550D03*
Y1966550D03*
Y1971050D03*
X304500Y44500D03*
X303300Y39500D03*
X308700Y39800D03*
X308800Y46400D03*
X308499Y72550D03*
X303999Y74050D03*
X307999Y78550D03*
X305998Y352114D03*
X306999Y758050D03*
X305998Y1569114D03*
X306999Y1932550D03*
X302499D03*
X298499D03*
X305999Y1964050D03*
Y1969550D03*
X326301Y1766030D03*
X334999Y1797050D03*
X356499Y113050D03*
X351999D03*
X347499D03*
X355999Y100550D03*
X350999D03*
X345999D03*
X371999Y15550D03*
X376499D03*
X369999Y23550D03*
Y19050D03*
X376999Y65550D03*
Y70050D03*
X360999Y113050D03*
Y100550D03*
X380999Y15550D03*
X382499Y20050D03*
X381499Y65550D03*
Y70050D03*
X544300Y1784638D03*
X557999Y322550D03*
Y326550D03*
X558099Y335050D03*
X557933Y331010D03*
X558499Y616050D03*
X554304Y615840D03*
X554499Y624550D03*
X558699D03*
X554499Y620050D03*
X558709Y620245D03*
X563499Y1486550D03*
Y1492050D03*
Y1497550D03*
Y1503550D03*
X633837Y1807384D03*
X717000Y1812384D03*
X757999Y154550D03*
Y159050D03*
X753999Y154550D03*
Y159050D03*
X755499Y314550D03*
X755346Y319149D03*
X751539Y313984D03*
X751499Y318050D03*
Y679148D03*
X749499Y716050D03*
X744999Y715550D03*
X749999Y720050D03*
X745499D03*
X755499Y1119050D03*
X749999Y1119550D03*
X748999Y1115550D03*
X748499Y1111550D03*
X751000Y1517000D03*
X757500Y1522500D03*
X751000Y1521000D03*
Y1525000D03*
X756900Y1766000D03*
X752900D03*
X751999Y1775550D03*
X756617Y1780067D03*
X752657Y1779496D03*
X755999Y1775550D03*
X753558Y1769946D03*
X757518Y1770517D03*
X781478Y363924D03*
X776978D03*
X772478Y359924D03*
Y363924D03*
X771196Y764382D03*
Y760382D03*
X775696Y764382D03*
X780196D03*
X780333Y1165892D03*
X775833D03*
X771333Y1161892D03*
Y1165892D03*
X778327Y1569796D03*
X773327Y1565796D03*
X773827Y1569796D03*
X767159Y1792364D03*
X773999Y1923550D03*
X767999Y1923050D03*
X774499Y1930050D03*
X768999D03*
X775814Y1975699D03*
X770814Y1971713D03*
X771814Y1975713D03*
X796873Y307571D03*
Y303071D03*
Y298571D03*
Y294071D03*
X784478Y355424D03*
Y359924D03*
X794331Y698353D03*
Y702853D03*
Y707353D03*
Y711853D03*
X799385Y761436D03*
X783196Y760382D03*
Y755882D03*
X802499Y1097566D03*
X798499D03*
X783333Y1157392D03*
Y1161892D03*
X795999Y1509550D03*
Y1504550D03*
Y1518550D03*
Y1514050D03*
X785827Y1561296D03*
Y1565796D03*
X782827Y1569796D03*
X795526Y1909696D03*
X795493Y1913696D03*
X795501Y1917696D03*
X795499Y1922050D03*
X783814Y1967213D03*
Y1971713D03*
X784016Y1975708D03*
X809373Y307571D03*
Y297571D03*
Y292571D03*
X808999Y303050D03*
X806831Y701853D03*
Y706853D03*
X806999Y697050D03*
X806831Y711853D03*
X811499Y1097050D03*
X807499D03*
X807341Y1111216D03*
Y1101216D03*
X806999Y1106050D03*
X807341Y1116216D03*
X809245Y1508722D03*
Y1503722D03*
Y1518722D03*
X808999Y1513550D03*
X807936Y1914865D03*
Y1910365D03*
X807997Y1922865D03*
X808005Y1918865D03*
X839999Y46050D03*
X840499Y55050D03*
X840999Y62550D03*
X841499Y71550D03*
X843499Y82550D03*
X838999Y85050D03*
X837999Y91050D03*
X838499Y107050D03*
Y99550D03*
X839499Y119050D03*
X865499Y39550D03*
X854499D03*
X856499Y71050D03*
X855499Y82050D03*
X845999Y111050D03*
X865499Y125550D03*
X864414Y1940050D03*
X883999Y39050D03*
X881499Y70550D03*
X866999D03*
X876999Y82050D03*
X867499D03*
X886499Y99550D03*
Y104550D03*
X875499Y125550D03*
X866499Y724550D03*
X873499Y1356050D03*
X882700Y1738300D03*
X886900Y1737900D03*
X902999Y22050D03*
X902499Y35050D03*
X905499Y56550D03*
X904999Y61550D03*
X904499Y74050D03*
X904999Y67550D03*
X890459Y100116D03*
X890499Y104550D03*
X903999Y574378D03*
X904814Y1789113D03*
X917499Y21550D03*
X909499D03*
X909999Y35550D03*
X916499Y36050D03*
X928499Y51550D03*
X928999Y56050D03*
X928499Y60550D03*
X928999Y65550D03*
X929999Y32550D03*
X940499Y33050D03*
X945499Y33550D03*
X943499Y48050D03*
Y55050D03*
Y72550D03*
X942999Y61550D03*
Y66550D03*
X943499Y78050D03*
X950100Y1626100D03*
X972000Y1442000D03*
Y1437500D03*
X971700Y1448300D03*
X962500Y1436500D03*
Y1441000D03*
X952800Y1437500D03*
Y1442000D03*
X962200Y1447300D03*
X952500Y1448300D03*
X971500Y1467500D03*
X971700Y1457800D03*
Y1462300D03*
Y1452800D03*
X962000Y1466500D03*
X952300Y1467500D03*
X962200Y1451800D03*
X952500Y1452800D03*
X962200Y1456800D03*
Y1461300D03*
X952500Y1457800D03*
Y1462300D03*
X966000Y1475000D03*
X958800Y1472500D03*
X966000Y1479500D03*
Y1484000D03*
X958800Y1477000D03*
Y1481500D03*
X965700Y1489300D03*
X958500Y1486800D03*
X960200Y1495300D03*
X951500D03*
X960049Y1500300D03*
X951349D03*
X960049Y1504800D03*
X951349D03*
X973500Y1483000D03*
Y1478500D03*
X973200Y1488300D03*
X973500Y1474000D03*
X972549Y1502300D03*
Y1506800D03*
X972700Y1497300D03*
G54D22*
X185999Y250550D03*
X168999Y413050D03*
X188499Y413550D03*
X205938Y72528D03*
X191999Y221550D03*
X203499Y250550D03*
X209499Y412550D03*
X210605Y70692D03*
X210685Y74725D03*
X215138Y72559D03*
X210634Y66863D03*
X210638Y62959D03*
X210738Y82159D03*
Y78459D03*
X210999Y221550D03*
X217999Y250550D03*
X232400Y220700D03*
X232999Y414550D03*
X252499Y415050D03*
X251499Y446050D03*
X231999Y445550D03*
X251999Y462050D03*
X232499Y461550D03*
X271999Y216050D03*
X265999Y245050D03*
X269999Y415050D03*
X272499Y445050D03*
X272999Y461050D03*
X290999Y216050D03*
X283499Y245050D03*
X284499Y415050D03*
X286999Y462050D03*
X292999Y483550D03*
X310499Y216550D03*
X297999Y245050D03*
X303999Y415550D03*
X306100Y462000D03*
X312499Y484050D03*
X337499Y282550D03*
X324999Y414550D03*
X327900Y463200D03*
X333499Y483050D03*
X343999Y190050D03*
X355499Y219050D03*
X337999D03*
X343499Y253550D03*
X354999Y282550D03*
X362999Y190050D03*
X369999Y219050D03*
X362499Y253550D03*
X369499Y282550D03*
X382499Y190550D03*
X381999Y254050D03*
X415999Y518550D03*
X438999Y381550D03*
X435499Y519050D03*
X448999Y255550D03*
X444499Y283050D03*
X463999Y283550D03*
X443499Y354050D03*
X464499Y353050D03*
X458499Y382050D03*
X456499Y518050D03*
X469999Y254550D03*
X481499Y283550D03*
X483499Y353050D03*
X485000Y373200D03*
X484900Y394700D03*
X488999Y254550D03*
X495999Y283550D03*
X502999Y353550D03*
X508499Y255050D03*
X525999D03*
X515499Y284050D03*
X520499Y353550D03*
X509999Y382550D03*
X514499Y546050D03*
X540499Y255050D03*
X536499Y283050D03*
X548100Y362200D03*
X530999Y381550D03*
X535499Y545050D03*
X538999Y562050D03*
X558499Y562550D03*
X579499Y561550D03*
X606499Y584550D03*
X625999Y585050D03*
X646999Y584550D03*
X674999Y601550D03*
X699999Y610050D03*
X721499Y617550D03*
X744999Y626550D03*
X757400Y686300D03*
X777499Y638050D03*
Y664550D03*
X771800Y686600D03*
X785499Y641050D03*
X794999Y664550D03*
X786500Y686100D03*
X798000Y686400D03*
X809700Y686300D03*
X806300Y670600D03*
X841000Y671100D03*
X923761Y85550D03*
X928561Y95181D03*
X928428Y83714D03*
X928508Y87747D03*
X928561Y91481D03*
X928457Y79885D03*
X928461Y75981D03*
X932961Y85581D03*
G54D11*
X17600Y5604D03*
X15499Y328050D03*
Y342550D03*
Y360050D03*
X14799Y751450D03*
X8599Y751650D03*
X17299Y773950D03*
X10999Y774050D03*
X18099Y1343550D03*
X9399Y1347350D03*
X15299Y1723450D03*
X15399Y1708350D03*
X7099Y1717750D03*
X7199Y1731450D03*
X14899Y1736250D03*
X15299Y1753250D03*
X6099Y1753750D03*
X11299Y1850050D03*
X9099Y1881550D03*
X14999Y1940050D03*
X8499Y1979550D03*
X11500Y1987000D03*
X36000Y5604D03*
X23499Y27050D03*
X40999Y27550D03*
X27799Y38450D03*
X40999Y42050D03*
X25799Y64050D03*
X28399Y94950D03*
X34999Y108550D03*
X41399Y134150D03*
X27999Y131050D03*
Y145550D03*
Y163050D03*
X23999Y243550D03*
Y229050D03*
Y261050D03*
X39999Y327550D03*
Y342050D03*
Y359550D03*
X29699Y388484D03*
X29599Y382884D03*
X23399Y373931D03*
Y389679D03*
X23499Y381831D03*
X29999Y398684D03*
X29899Y404384D03*
X23799Y405684D03*
X23499Y397579D03*
X28672Y429356D03*
X29365Y421169D03*
X23399Y429051D03*
X28700Y451900D03*
X28800Y436700D03*
X28700Y445700D03*
X23399Y444799D03*
X23499Y452699D03*
Y436951D03*
X29500Y460800D03*
X23499Y468447D03*
X23399Y476295D03*
Y460547D03*
Y492043D03*
X23499Y484195D03*
X28600Y508500D03*
X38400Y514955D03*
X28664Y499429D03*
X23499Y515691D03*
Y499943D03*
X23399Y507791D03*
X35338Y524746D03*
X26691Y532701D03*
X22800Y539600D03*
X23399Y523539D03*
X23499Y531439D03*
X39999Y576550D03*
X22699Y577950D03*
X22999Y565550D03*
X22978Y588571D03*
X26869Y616861D03*
X23499Y618053D03*
X23999Y609250D03*
X34976Y619250D03*
X30712Y624971D03*
X29999Y640550D03*
X29819Y634951D03*
X23399Y641649D03*
X23799Y625950D03*
X23499Y633801D03*
X30999Y656250D03*
Y650550D03*
X23499Y665297D03*
Y649549D03*
X23725Y657471D03*
X23699Y673150D03*
X23499Y681045D03*
X29999Y694550D03*
X25999Y694870D03*
X23999Y689050D03*
X26399Y750850D03*
X39899Y754850D03*
X39399Y768750D03*
X27199Y764950D03*
X28599Y775450D03*
X26299Y815050D03*
X22500Y853700D03*
X26799Y874550D03*
X26099Y891650D03*
X25699Y916150D03*
X25099Y942150D03*
X23899Y957950D03*
X24799Y992250D03*
X33899Y1005950D03*
X20400Y1048300D03*
X23700Y1354600D03*
X22851Y1374169D03*
X22999Y1366050D03*
X23499Y1381550D03*
X32550Y1392777D03*
X27499Y1387550D03*
X24499Y1389663D03*
X33321Y1414755D03*
X29786Y1414858D03*
X23499Y1421550D03*
X23999Y1413550D03*
X36198Y1446749D03*
X27099Y1444350D03*
X30999Y1438050D03*
X27999Y1430050D03*
X23499Y1445050D03*
X22999Y1437050D03*
X23999Y1429050D03*
X29069Y1459379D03*
X36791Y1460866D03*
X23028Y1468579D03*
X23499Y1460550D03*
X22999Y1453050D03*
X32520Y1485092D03*
X28999Y1478050D03*
X23599Y1476350D03*
X23277Y1484050D03*
X27499Y1495050D03*
X36999Y1494550D03*
X22999Y1500050D03*
X23799Y1508050D03*
X24499Y1492050D03*
X35245Y1522512D03*
X35999Y1514550D03*
X29765Y1515282D03*
X24423Y1527123D03*
X22999Y1515550D03*
X25247Y1546912D03*
X24999Y1569550D03*
X31149Y1568300D03*
X23608Y1572653D03*
X24323Y1559950D03*
X22699Y1594224D03*
X31099Y1595350D03*
X26999Y1610550D03*
X34884Y1615734D03*
X23499Y1618050D03*
Y1610050D03*
Y1602050D03*
X32199Y1633124D03*
X34816Y1630953D03*
X22999Y1626050D03*
X23499Y1634050D03*
X27499Y1657050D03*
X32989Y1648451D03*
X26785Y1642089D03*
X23499Y1657050D03*
X23999Y1649550D03*
X23415Y1641634D03*
X34699Y1663300D03*
X22999Y1665550D03*
X24244Y1681868D03*
X22864Y1673550D03*
X31499Y1849750D03*
X22099Y1836609D03*
X39399Y1864350D03*
X23999Y1857950D03*
X27199Y1874350D03*
X34799Y1890050D03*
X28799Y1919060D03*
X34799Y1946750D03*
X38703Y1946754D03*
X26500Y1987000D03*
X55700Y5900D03*
X50999Y21150D03*
Y47750D03*
X59499Y90550D03*
Y76050D03*
Y108050D03*
X52499Y130550D03*
Y145050D03*
Y162550D03*
X41699Y183250D03*
X41999Y200050D03*
X48499Y243050D03*
Y228550D03*
Y260550D03*
X42999Y275650D03*
X51099Y300050D03*
X52199Y342350D03*
X47543Y578340D03*
X44959Y575756D03*
X42299Y564150D03*
X62055Y561550D03*
X49555Y563550D03*
X61099Y603236D03*
X60076Y595777D03*
X55499Y595650D03*
X52333Y641295D03*
X57800Y634300D03*
X44900Y642800D03*
X47800Y692800D03*
X53210Y701486D03*
X53999Y791000D03*
X47400Y1721700D03*
X42000Y1740100D03*
X47717Y1731337D03*
X47800Y1740500D03*
X60449Y1842550D03*
X52999Y1871550D03*
X57499Y1871050D03*
X45699Y1875550D03*
X44368Y1951450D03*
X44399Y1942250D03*
X42532Y1946783D03*
X53999Y1946650D03*
X50299D03*
X46565Y1946703D03*
X45999Y1971450D03*
X61500Y1987500D03*
X44500Y1987000D03*
X55999Y1982550D03*
X73900Y6200D03*
X65499Y27050D03*
Y41550D03*
Y59050D03*
X77165Y110799D03*
X71015Y123666D03*
X78165Y137116D03*
X75299Y261750D03*
X76099Y414250D03*
X75300Y454100D03*
X67300Y450200D03*
X68899Y445450D03*
X66199Y475184D03*
Y469884D03*
X77499Y469550D03*
X66299Y490784D03*
Y485484D03*
X77999Y493050D03*
X66099Y500950D03*
X77165Y514650D03*
X77499Y502550D03*
X63499Y538550D03*
Y533050D03*
X70800Y540300D03*
X75999Y556640D03*
X72599Y578236D03*
X74499Y662050D03*
X78499Y654050D03*
X81999Y668050D03*
X79299Y794150D03*
X67999Y790400D03*
X76399Y820450D03*
X70100Y818900D03*
X77499Y921550D03*
X77002Y952079D03*
X76711Y948089D03*
X77499Y962152D03*
X72799Y982950D03*
X65799Y994050D03*
X80000Y1090500D03*
X74500Y1097550D03*
X79899Y1104550D03*
X74399Y1111550D03*
X78499Y1273550D03*
X78613Y1282664D03*
X78779Y1302664D03*
Y1312664D03*
X77165Y1327335D03*
X77166Y1353400D03*
X76499Y1507050D03*
Y1498050D03*
Y1512050D03*
Y1503050D03*
X76999Y1528050D03*
Y1519050D03*
X78100Y1688189D03*
X83599Y1744750D03*
X77165Y1759550D03*
X78529Y1788113D03*
X79500Y1987500D03*
X65499Y1982550D03*
X73499D03*
X82999D03*
X90900Y5800D03*
X90899Y14850D03*
X93999Y58550D03*
X92900Y66128D03*
X92999Y86128D03*
Y96128D03*
X89603Y132629D03*
X95814Y136065D03*
X96184Y151065D03*
Y166065D03*
X92899Y231450D03*
X86899Y242750D03*
X93199Y279650D03*
X84899Y289250D03*
X90899Y309550D03*
X94199Y325550D03*
X93499Y337450D03*
X89899Y368350D03*
X95499Y355450D03*
X89999Y396450D03*
X87599Y403950D03*
X95399Y416350D03*
X89099Y426150D03*
X99399Y437450D03*
X96900Y510000D03*
X93200Y510500D03*
X83700Y529500D03*
X88999Y538050D03*
X104502Y530552D03*
X101500Y536500D03*
X93599Y581236D03*
X93100Y571640D03*
X92599Y606236D03*
X92999Y868550D03*
X92499Y876550D03*
X93499Y897152D03*
X93000Y907165D03*
X89469Y935588D03*
X83988Y934028D03*
X89499Y942850D03*
X86700Y982100D03*
X102999Y1188050D03*
X104999Y1231050D03*
X100999Y1231032D03*
X103499Y1305050D03*
X102000Y1341000D03*
X91279Y1340642D03*
X86165Y1339050D03*
X101500Y1352000D03*
X89999Y1348050D03*
X93316Y1351000D03*
X96000Y1369000D03*
X96100Y1384650D03*
X100499Y1479650D03*
X90999Y1628550D03*
Y1624550D03*
X91121Y1632549D03*
X86299Y1632550D03*
X85999Y1628550D03*
Y1624550D03*
X92900Y1678176D03*
X92873Y1708176D03*
X92479Y1718176D03*
X84099Y1737150D03*
X89306Y1746856D03*
X89499Y1753575D03*
X93499Y1759550D03*
X94336Y1773113D03*
X104417Y1791480D03*
X97999Y1815050D03*
X104500Y1813400D03*
X101699Y1983850D03*
X98000Y1987500D03*
X91499Y1983050D03*
X107000Y6000D03*
X112999Y124050D03*
X111790Y132259D03*
X123499Y149050D03*
Y140050D03*
X117500Y162300D03*
X124300Y167800D03*
X114900Y177900D03*
X124999Y246050D03*
X123378Y255944D03*
X109499Y410250D03*
X124899Y409050D03*
X126099Y396150D03*
X111299Y425850D03*
X122499Y427900D03*
X107526Y528996D03*
X108599Y557236D03*
X108900Y587600D03*
X124999Y643050D03*
X112200Y762200D03*
X112000Y773000D03*
X111299Y821050D03*
X112999Y901150D03*
X106749Y934367D03*
X108441Y924705D03*
X106500Y943000D03*
X105300Y960300D03*
X124100Y1047100D03*
X120100Y1053200D03*
X121500Y1083600D03*
X121100Y1075300D03*
X117499Y1079300D03*
X116249Y1102550D03*
X112999Y1103740D03*
X106999Y1114960D03*
X120999Y1188050D03*
X111999D03*
X114999Y1210363D03*
X121657Y1224604D03*
X120999Y1228550D03*
X118999Y1219050D03*
X120499Y1264550D03*
X123938Y1267623D03*
X117149Y1267550D03*
X111499Y1311800D03*
X113000Y1341000D03*
X107228Y1330552D03*
X107500Y1340500D03*
X113500Y1352000D03*
X110499Y1365050D03*
X109999Y1355050D03*
X119507Y1423540D03*
X107328Y1438218D03*
X114499Y1432050D03*
X107999Y1448050D03*
X105099Y1459150D03*
X123999Y1473050D03*
X122199Y1476050D03*
X124999Y1616050D03*
Y1620050D03*
Y1629050D03*
Y1633050D03*
X119999Y1629050D03*
X120100Y1633100D03*
X122499Y1668550D03*
Y1672550D03*
X118999Y1670550D03*
X104999Y1708963D03*
X117249Y1712090D03*
X107499Y1736550D03*
X106999Y1746290D03*
X120299Y1796150D03*
X111499Y1877550D03*
Y1882550D03*
X122999Y1883050D03*
X115999Y1882550D03*
X116499Y1877550D03*
X122999Y1889050D03*
X108499Y1981750D03*
X115000Y1987000D03*
X127999Y157050D03*
X133999Y149050D03*
X142999Y141050D03*
X132999Y141550D03*
X144499Y149050D03*
X131799Y201950D03*
X142688Y218861D03*
X143110Y203861D03*
X133000Y240500D03*
X147099Y245350D03*
X135399Y277050D03*
X130799Y300250D03*
X130099Y326150D03*
X134699Y356050D03*
X139399Y372350D03*
X133499Y445050D03*
X128999Y445550D03*
X130000Y452000D03*
X139200Y484300D03*
X134499Y488050D03*
X138999Y524213D03*
X140000Y587700D03*
X140499Y600550D03*
X143999Y605550D03*
X128725Y636626D03*
X128479Y640589D03*
X141773Y643013D03*
X140499Y626050D03*
Y649350D03*
X134300Y646400D03*
X131099Y700450D03*
X139099Y707150D03*
X141500Y711000D03*
X141234Y1029885D03*
X140864Y1044885D03*
X137100Y1084800D03*
X140800Y1076300D03*
X137900Y1103400D03*
X139100Y1097100D03*
X134500Y1108100D03*
X143200Y1116300D03*
X133200Y1132100D03*
X126400Y1138100D03*
X145900Y1163200D03*
X144399Y1171150D03*
X141499Y1185550D03*
X128400Y1188600D03*
X143899Y1196750D03*
X142499Y1205550D03*
X130999Y1198050D03*
X130699Y1210653D03*
X126499Y1264550D03*
X125999Y1315550D03*
X132999Y1319550D03*
X142667Y1319218D03*
X133475Y1331200D03*
X145999Y1353050D03*
X138000Y1359025D03*
X143199Y1412050D03*
X140799Y1435460D03*
X139815Y1454438D03*
X139235Y1460973D03*
X127898Y1462441D03*
X126562Y1670613D03*
X141500Y1715500D03*
X126599Y1789650D03*
X142144Y1801644D03*
X141101Y1866545D03*
X140999Y1859550D03*
X143490Y1855972D03*
X127499Y1889050D03*
X126999Y1882550D03*
X135999Y1881550D03*
X142499Y1905972D03*
X141499Y1895972D03*
X146899Y1961750D03*
X146000Y1987500D03*
X128500D03*
X157299Y5150D03*
X152999Y141050D03*
X167499Y149550D03*
X163499Y140050D03*
X160999Y149550D03*
X152499D03*
X166800Y240800D03*
X158999Y259800D03*
X152808Y246341D03*
X157740Y273924D03*
X157440Y283924D03*
Y303924D03*
Y313924D03*
X167299Y369350D03*
X150699Y411050D03*
X152499Y395950D03*
X165699Y428050D03*
X153459Y427494D03*
X154101Y445550D03*
X163449Y521650D03*
X154099Y529236D03*
X160932Y549468D03*
X162500Y623400D03*
X161000Y639100D03*
X152400Y643300D03*
X152124Y651868D03*
X159054Y665400D03*
X158885Y679436D03*
Y689436D03*
X158385Y719436D03*
X159500Y814700D03*
X161999Y843550D03*
Y848050D03*
X156499Y846050D03*
X156999Y850050D03*
X158114Y883290D03*
X156499Y886950D03*
X160399Y922850D03*
X153299Y943750D03*
X156499Y985950D03*
X149499Y997650D03*
X162499Y1023550D03*
X158300Y1015000D03*
X163499Y1035050D03*
X159499Y1044579D03*
X165600Y1057428D03*
X168099Y1083550D03*
X164999Y1075550D03*
X159055Y1070400D03*
X159000Y1083000D03*
X167999Y1092850D03*
X167499Y1118550D03*
X167999Y1130550D03*
X157700Y1114948D03*
X157600Y1124948D03*
X163499Y1171650D03*
X151699Y1158550D03*
X151499Y1173050D03*
X150999Y1181150D03*
X149562Y1315987D03*
X167499Y1389050D03*
X156999Y1397750D03*
X166799Y1409350D03*
X157915Y1420460D03*
X163499Y1433350D03*
X165499Y1453550D03*
X150338Y1453958D03*
X152499Y1462940D03*
X166799Y1487450D03*
X157440Y1490460D03*
X159054Y1476200D03*
X157440Y1500460D03*
Y1520460D03*
Y1530460D03*
X165575Y1676975D03*
X157500Y1797400D03*
X158000Y1825400D03*
X157999Y1840972D03*
X167200Y1868000D03*
X159054Y1855050D03*
X163599Y1892050D03*
X168299Y1879850D03*
X159054Y1881800D03*
X159173Y1935972D03*
X159421Y1925972D03*
X148499Y1977250D03*
X163500Y1987500D03*
X189499Y4550D03*
X168499Y65550D03*
X175999Y82428D03*
X169999Y129050D03*
X176499Y140050D03*
X173499Y149050D03*
X177899Y199250D03*
X181299Y267350D03*
X187199Y359050D03*
X181599Y396250D03*
X173100Y483100D03*
X182499Y532550D03*
X168453Y527949D03*
X181999Y624050D03*
Y609550D03*
Y641550D03*
X182599Y688350D03*
X171999Y672450D03*
X170799Y689150D03*
X178899Y765250D03*
X172599Y774250D03*
X172660Y815731D03*
X168499Y846713D03*
X173899Y846550D03*
X174199Y841050D03*
X172099Y877450D03*
X169299Y956350D03*
X171499Y998650D03*
X169299Y1067150D03*
X171599Y1139950D03*
X180400Y1202800D03*
X181700Y1219900D03*
X179800Y1244100D03*
X179500Y1262000D03*
X178200Y1393400D03*
X180599Y1424050D03*
X180000Y1439500D03*
X176599Y1447450D03*
X172299Y1465850D03*
X181500Y1479000D03*
X176299Y1500150D03*
X179999Y1655887D03*
X181900Y1675300D03*
X180701Y1716050D03*
X179701Y1724550D03*
X180000Y1731000D03*
X185999Y1746050D03*
X182299Y1801350D03*
X173899Y1813250D03*
X177599Y1866750D03*
X168499Y1855550D03*
X181099Y1885850D03*
X168699Y1957150D03*
X183999Y1968150D03*
X188199Y1978250D03*
X183000Y1987500D03*
X206999Y5050D03*
X191999Y68050D03*
X201499Y104550D03*
X206899Y171650D03*
X190199Y178650D03*
X197899Y165075D03*
X201199Y266750D03*
X209199Y365050D03*
X209999Y426150D03*
X205300Y508100D03*
X190499Y507513D03*
X193549Y575875D03*
X206499Y623550D03*
Y609050D03*
X207300Y639400D03*
X199199Y659150D03*
X190399Y689050D03*
X209500Y759000D03*
X208799Y766750D03*
X190699Y778350D03*
X197099Y795050D03*
X208299Y805350D03*
X202900Y811900D03*
X198199Y805950D03*
X200000Y818000D03*
X200539Y890300D03*
X198499Y884113D03*
X204699Y929450D03*
X206699Y953050D03*
X203999Y943350D03*
X205999Y978250D03*
X198924Y975975D03*
X206299Y990250D03*
X207299Y1008150D03*
X202100Y1028100D03*
X199499Y1093850D03*
X209900Y1093600D03*
X208199Y1145850D03*
X210199Y1173450D03*
X204199Y1163850D03*
X201600Y1205900D03*
X196499Y1215550D03*
Y1196550D03*
X196399Y1236650D03*
X196499Y1224550D03*
X195499Y1251050D03*
X202199Y1276850D03*
X195499Y1279050D03*
Y1270050D03*
X202899Y1291450D03*
X207699Y1337950D03*
X195500Y1352500D03*
X208049Y1385550D03*
X203199Y1393250D03*
X204699Y1418350D03*
X201000Y1408500D03*
X194200Y1457900D03*
X204999Y1472650D03*
X208999Y1491250D03*
X202399Y1500750D03*
X209200Y1624000D03*
X193500Y1647000D03*
X200600Y1663600D03*
X199900Y1670600D03*
X193499Y1674050D03*
X197600Y1694900D03*
X204400Y1688200D03*
X209901Y1691850D03*
X201801Y1701450D03*
X195001Y1708150D03*
X205200Y1708000D03*
X195500Y1717000D03*
X195000Y1725500D03*
X206900Y1726700D03*
X199699Y1761450D03*
X205199Y1801950D03*
X194049Y1792600D03*
X209999Y1825050D03*
X192100Y1813500D03*
X204399Y1855450D03*
X206999Y1867550D03*
X207199Y1892850D03*
X191599Y1891550D03*
X199599Y1879850D03*
X205499Y1968650D03*
X190199Y1957650D03*
X199600Y1974900D03*
X209699Y1978750D03*
X199000Y1987500D03*
X226499Y5050D03*
X229099Y161350D03*
X213499Y283864D03*
X214063Y318114D03*
X223799Y365350D03*
X213400Y355300D03*
X224998Y357049D03*
X217599Y396450D03*
X218499Y474850D03*
X224299Y494650D03*
X220499Y560050D03*
Y545550D03*
Y577550D03*
X224999Y613450D03*
X219999Y632550D03*
Y647050D03*
X226399Y677550D03*
X212999Y677350D03*
X218800Y668700D03*
X216999Y686550D03*
X213999Y725050D03*
X230849Y726050D03*
X224099Y770250D03*
X228999Y765550D03*
X218224Y765325D03*
X214799Y774750D03*
X227199Y795050D03*
X217300Y816800D03*
X229562Y904113D03*
X215499Y905550D03*
X225299Y957650D03*
X213999Y958650D03*
X217499Y981050D03*
X216999Y967550D03*
X217499Y998550D03*
X217999Y1012050D03*
X215999Y1039550D03*
X216499Y1053050D03*
X221300Y1083238D03*
X214499Y1154250D03*
X223099Y1182750D03*
X212499Y1184550D03*
Y1212550D03*
X221599Y1237250D03*
X220999Y1224350D03*
X222299Y1251850D03*
X229899Y1250550D03*
X211499Y1258050D03*
Y1239050D03*
X216300Y1274800D03*
X211499Y1267050D03*
X219099Y1325950D03*
X226599Y1340250D03*
X213199Y1350050D03*
X227399Y1363050D03*
X217499Y1387450D03*
X230599Y1400250D03*
X217999Y1408850D03*
X227999Y1421550D03*
X226300Y1447800D03*
X230899Y1437350D03*
X212400Y1433700D03*
X213399Y1500300D03*
X212899Y1535550D03*
X230999D03*
X211999Y1568550D03*
X231499Y1575050D03*
X224499D03*
X217999Y1574550D03*
X211999D03*
X218000Y1614300D03*
X228999Y1637550D03*
X211999Y1653550D03*
X230600Y1670500D03*
X213000Y1672500D03*
X216601Y1684350D03*
X226800Y1684200D03*
X220100Y1691700D03*
X212000Y1701300D03*
X222700Y1710100D03*
X222499Y1743850D03*
X221499Y1760950D03*
X220799Y1791550D03*
X215299Y1813950D03*
X224800Y1867000D03*
X228999Y1856050D03*
X212399Y1885850D03*
X213562Y1926113D03*
X220062Y1931113D03*
X227499Y1971050D03*
X221300Y1971200D03*
X225199Y1978750D03*
X216999Y1987550D03*
X241999Y5050D03*
X247499Y37550D03*
X246999Y46550D03*
Y51550D03*
X246499Y42550D03*
X246999Y56050D03*
X247499Y65050D03*
X246999Y69550D03*
Y60550D03*
X246499Y86050D03*
Y80550D03*
X245499Y100550D03*
X244499Y136550D03*
Y122050D03*
X244900Y149100D03*
X249800Y248800D03*
X235399Y263350D03*
X231800Y318414D03*
X233998Y357549D03*
X239400Y357400D03*
X237699Y426050D03*
X244199Y483350D03*
X242099Y511750D03*
X244999Y559550D03*
Y545050D03*
Y577050D03*
X244499Y632050D03*
X246500Y663300D03*
X245000Y647000D03*
X234200Y668300D03*
X252499Y726050D03*
X241600Y765700D03*
X236800Y765800D03*
X245599Y773450D03*
X234299Y773750D03*
X247099Y795050D03*
X233799Y806350D03*
X245399Y823550D03*
X244099Y857450D03*
X252399Y838250D03*
X245199Y878050D03*
X232399Y886550D03*
X252899Y886350D03*
X245399Y907450D03*
X243899Y923650D03*
X242199Y938750D03*
X252499Y948850D03*
X244199Y973250D03*
X232299Y981950D03*
X233499Y966050D03*
X245899Y995250D03*
X233999Y997050D03*
Y1012550D03*
X232499Y1038050D03*
X249499Y1104150D03*
X232599Y1195750D03*
X251999Y1184550D03*
X242199Y1210050D03*
X242599Y1198350D03*
X247899Y1208650D03*
X234299Y1232650D03*
X250900Y1248500D03*
X242900Y1263000D03*
X232799Y1276150D03*
X241399Y1303250D03*
X239099Y1314150D03*
X252399Y1326350D03*
X245999Y1339050D03*
Y1358050D03*
X234300Y1375700D03*
X246499Y1370050D03*
X249800Y1388400D03*
X244999Y1412550D03*
X245499Y1424550D03*
X238899Y1453750D03*
X248000Y1482000D03*
X250199Y1473550D03*
X247500Y1499000D03*
X232650Y1493450D03*
X236999Y1535550D03*
X238300Y1575100D03*
X246200Y1617600D03*
X239400Y1624300D03*
X242999Y1658050D03*
X237400Y1663800D03*
X235499Y1697050D03*
X249199Y1743150D03*
X237999Y1730550D03*
X244999Y1755050D03*
X252199Y1793050D03*
X238699Y1801850D03*
X241199Y1867150D03*
X244700Y1878700D03*
X232314Y1890513D03*
X236225Y1883125D03*
X241255Y1896055D03*
X240964Y1934113D03*
X238999Y1970550D03*
X232999Y1971050D03*
X240900Y1979000D03*
X236500Y1987500D03*
X261499Y4550D03*
X253999Y48050D03*
Y44050D03*
X264999Y55350D03*
X261299Y75950D03*
X258699Y104550D03*
X265299Y96250D03*
X262299Y164050D03*
X262699Y208550D03*
X252935Y319114D03*
X258999Y396650D03*
X266699Y425050D03*
X266199Y472350D03*
X257499Y498050D03*
Y512550D03*
Y530050D03*
X256499Y577050D03*
Y591550D03*
Y609050D03*
X269499Y616550D03*
X257199Y640050D03*
X269499Y631050D03*
Y648550D03*
X268099Y795450D03*
X254699Y807650D03*
X264499Y829050D03*
X264999Y842550D03*
Y858450D03*
X265799Y901850D03*
X256199Y916250D03*
X254899Y929250D03*
X253499Y938050D03*
X269599Y923950D03*
X267199Y935350D03*
X264799Y946850D03*
X263299Y959350D03*
X272999Y981050D03*
Y965550D03*
X256499Y967050D03*
X262499Y995850D03*
X254499Y984550D03*
X258999Y1011550D03*
X269999Y1037050D03*
X253499Y1038550D03*
X269999Y1052550D03*
X253999Y1052050D03*
X272999Y1102850D03*
X262499Y1129150D03*
X255000Y1125700D03*
X260349Y1139200D03*
X256000Y1133000D03*
X272999Y1214150D03*
X261199Y1227950D03*
X264800Y1261300D03*
X254899Y1289950D03*
X264799Y1313850D03*
X265299Y1339650D03*
X263699Y1359550D03*
X265499Y1376950D03*
X258999Y1396950D03*
X270599Y1408550D03*
X259299Y1438750D03*
X268499Y1453550D03*
X265700Y1635100D03*
X258700Y1645100D03*
X270999Y1660550D03*
X253999Y1676550D03*
X273499Y1694050D03*
X255699Y1722550D03*
X256499Y1710050D03*
X263499Y1734550D03*
X270599Y1748950D03*
X259499Y1760650D03*
X270599Y1801450D03*
X253899Y1813250D03*
X261499Y1825050D03*
X255999Y1855950D03*
X270299Y1867250D03*
X254500Y1987500D03*
X272000D03*
X278999Y5050D03*
X292999Y4550D03*
X291999Y94050D03*
X283599Y106250D03*
X274700Y131500D03*
X280999Y120050D03*
Y152050D03*
X294500Y339000D03*
X277799Y338599D03*
X276299Y376050D03*
X289399Y395750D03*
X291599Y446150D03*
X281999Y497550D03*
Y512050D03*
Y529550D03*
X277999Y545350D03*
X280999Y576550D03*
Y591050D03*
Y608550D03*
X293999Y616050D03*
Y630550D03*
Y648050D03*
X292999Y743650D03*
X277039Y740300D03*
X287799Y794850D03*
X275299Y806350D03*
X288899Y820550D03*
X280999Y827550D03*
X283599Y857450D03*
X293899Y843850D03*
X280999Y843050D03*
Y870050D03*
X281499Y883550D03*
X274299Y912950D03*
X287299Y901050D03*
X281099Y943550D03*
X278799Y956150D03*
X290099Y948650D03*
X289399Y963350D03*
X277599Y975250D03*
X288099Y971250D03*
X285399Y982950D03*
X294699Y989550D03*
X287099Y1000150D03*
X274999Y996550D03*
X289699Y1021750D03*
X275099Y1024750D03*
X274999Y1012050D03*
X287099Y1035050D03*
X282999Y1099550D03*
X274900Y1115600D03*
X290699Y1122650D03*
X283499Y1113050D03*
X276299Y1134550D03*
X283299Y1144850D03*
X291399Y1174150D03*
X279799Y1191750D03*
X286599Y1203750D03*
X283799Y1249250D03*
X274299Y1276450D03*
X281099Y1302850D03*
X286799Y1326450D03*
X286499Y1364050D03*
Y1345050D03*
X278799Y1386250D03*
X285499Y1399550D03*
X278000Y1422000D03*
X285499Y1418550D03*
Y1427550D03*
X286600Y1449700D03*
X286700Y1516100D03*
X289999Y1554650D03*
X293700Y1553351D03*
X276039Y1551300D03*
X291400Y1561500D03*
X278499Y1621550D03*
X289000Y1641800D03*
X284300Y1676900D03*
X291099Y1707450D03*
X280499Y1718550D03*
X285499Y1742550D03*
X290699Y1760750D03*
X286599Y1791850D03*
X284299Y1811150D03*
X295299Y1870250D03*
X283999Y1856050D03*
X280689Y1942710D03*
X291499Y1987550D03*
X310499Y5050D03*
X296099Y17100D03*
X305099Y17000D03*
X311400Y17100D03*
X306999Y55450D03*
X311299D03*
X315799Y55350D03*
X306100Y126500D03*
X307199Y205550D03*
X313199Y270350D03*
X313000Y313900D03*
X298800Y333000D03*
X313039Y352350D03*
X299899Y376650D03*
X310999Y396250D03*
X300899Y431850D03*
X298599Y501250D03*
X309399Y513450D03*
X297599Y519350D03*
X307499Y555550D03*
Y541050D03*
X297499Y551050D03*
X296199Y568550D03*
X307499Y573050D03*
X302899Y607950D03*
X307499Y661550D03*
Y647050D03*
X297699Y681850D03*
X307499Y679050D03*
X308899Y705150D03*
X298399Y703450D03*
X296399Y716950D03*
X308999Y716450D03*
X315999Y718950D03*
X298000Y743500D03*
X314499Y754550D03*
X307999Y803150D03*
X307899Y794550D03*
X300199Y835250D03*
X304899Y856150D03*
X313499Y847850D03*
X315199Y869450D03*
X297499Y868550D03*
X302499Y899050D03*
X297499Y884050D03*
X302199Y914650D03*
X315199Y925950D03*
X310699Y943550D03*
X299399Y965950D03*
X298099Y977250D03*
X307999Y970650D03*
X306699Y981250D03*
X304399Y997550D03*
X298399Y1008150D03*
X306399Y1020750D03*
X303699Y1038050D03*
X299999Y1052350D03*
X304699Y1057050D03*
X312299Y1093550D03*
X299499Y1098050D03*
Y1113550D03*
X316499Y1124550D03*
X307999Y1142050D03*
X304499Y1156650D03*
X313499Y1170150D03*
X300699Y1185150D03*
X315408Y1202663D03*
X311999Y1213850D03*
X300699Y1227350D03*
X310299Y1240050D03*
X304699Y1265850D03*
X312499Y1280350D03*
X295399Y1292950D03*
X300499Y1305350D03*
X311500Y1316300D03*
X297899Y1336150D03*
X298099Y1357250D03*
X311900Y1344900D03*
X301699Y1377950D03*
X312900Y1366900D03*
X301699Y1395750D03*
X313600Y1391300D03*
X303499Y1411250D03*
X312100Y1420700D03*
X300899Y1433350D03*
X313600Y1442700D03*
X304699Y1457550D03*
X312800Y1467400D03*
X296599Y1497150D03*
X312000Y1514600D03*
X314999Y1527550D03*
X297800Y1561600D03*
X312999Y1566050D03*
X307000Y1619600D03*
X302399Y1662950D03*
X299999Y1696050D03*
X303999Y1722050D03*
X297099Y1733850D03*
X303499Y1753550D03*
X303999Y1800850D03*
X315499Y1812250D03*
X298999Y1855950D03*
X313599Y1870250D03*
X308099Y1880550D03*
X313599Y1889250D03*
X314099Y1901250D03*
X305999Y1913050D03*
X302499Y1922050D03*
X313499Y1919050D03*
X296858Y1956228D03*
X315999Y1958550D03*
X311500Y1987500D03*
X329999Y5050D03*
X317000Y17300D03*
X332200Y94200D03*
X321799Y173950D03*
X317499Y192950D03*
X331499Y193250D03*
X325499Y249450D03*
X316999Y312576D03*
X321748Y343299D03*
X321900Y364600D03*
X328799Y372350D03*
X336099Y417550D03*
X322099Y426850D03*
X328599Y442250D03*
X329999Y510450D03*
X321999Y533150D03*
X331999Y555050D03*
Y540550D03*
X321999Y550550D03*
X321299Y565250D03*
X320799Y582050D03*
X331999Y572550D03*
X328599Y602450D03*
X328499Y635650D03*
X317999Y627850D03*
X331999Y661050D03*
Y646550D03*
Y678550D03*
X324599Y696150D03*
X330799Y712450D03*
X323249Y749010D03*
X324959Y766750D03*
X318999Y814350D03*
X325599Y823950D03*
X330299Y871850D03*
X323799Y859850D03*
X321099Y899650D03*
X323099Y885050D03*
X322099Y913650D03*
X331099Y923650D03*
X328099Y937250D03*
X323499Y956950D03*
X329799Y970650D03*
X333099Y983450D03*
X320999Y997250D03*
X331299Y1017150D03*
X321299Y1012450D03*
Y1024750D03*
X331599Y1028750D03*
X329599Y1040750D03*
X318299Y1038750D03*
X329599Y1057050D03*
X319999Y1066950D03*
X317699Y1054650D03*
X329299Y1098550D03*
X326599Y1112350D03*
X332999Y1123050D03*
X323999Y1153250D03*
X332999Y1138550D03*
X317999Y1137550D03*
X329799Y1182750D03*
X328999Y1200550D03*
X326649Y1227850D03*
Y1218850D03*
X327999Y1255050D03*
X333349Y1270500D03*
Y1288900D03*
Y1307000D03*
Y1332800D03*
Y1363500D03*
Y1393100D03*
Y1429500D03*
Y1481900D03*
X332500Y1519700D03*
X324000Y1562500D03*
X323999Y1577250D03*
X337199Y1636350D03*
X320299Y1642950D03*
X316799Y1657450D03*
X335767Y1662735D03*
X318499Y1675550D03*
X334399Y1691650D03*
X329999Y1716950D03*
X320999Y1706050D03*
X321999Y1733050D03*
X321499Y1772550D03*
X327299Y1791850D03*
X322299Y1802150D03*
X337499Y1855950D03*
X316999D03*
X336799Y1869950D03*
X326399Y1876250D03*
X336799Y1888950D03*
X326899Y1907250D03*
X326399Y1895250D03*
X336799Y1897950D03*
X335799Y1916450D03*
X325221Y1927272D03*
X329999Y1952273D03*
X326799Y1977050D03*
X327100Y1966472D03*
X329999Y1987550D03*
X345499Y5050D03*
X343499Y60150D03*
X357503Y77043D03*
X354099Y175350D03*
X343399Y161350D03*
X343799Y204550D03*
X355999Y242750D03*
X347699Y269050D03*
X347399Y301950D03*
X339399Y358050D03*
X357999Y359050D03*
X354099Y373050D03*
X338399Y395650D03*
X338899Y433850D03*
X354699Y426650D03*
X356399Y451750D03*
X351399Y470750D03*
X340799Y512050D03*
X358399Y498650D03*
X341399Y535850D03*
X357399Y521250D03*
Y530550D03*
X341399Y558950D03*
X357399Y543850D03*
X357999Y559450D03*
X340299Y586550D03*
X342199Y613050D03*
X342099Y646350D03*
X341899Y664950D03*
X342599Y678850D03*
X345399Y698950D03*
X357699Y707750D03*
X341399Y715050D03*
X355999Y752850D03*
X353999Y787750D03*
X347699Y773450D03*
X338099Y811650D03*
X338599Y821650D03*
Y840450D03*
X340099Y887350D03*
X338399Y901050D03*
X340099Y910350D03*
X340399Y931250D03*
X340099Y952850D03*
X339599Y1081550D03*
X344399Y1338150D03*
X343599Y1360050D03*
X344099Y1393750D03*
Y1421150D03*
Y1449550D03*
X351899Y1570850D03*
X344500Y1583600D03*
X350600Y1610900D03*
X349099Y1634550D03*
X351099Y1691150D03*
X352000Y1700400D03*
X343899Y1752650D03*
X357999Y1796050D03*
X355699Y1810750D03*
X351999Y1855450D03*
X348999Y1879050D03*
X349499Y1910050D03*
X348999Y1898050D03*
X347999Y1925550D03*
X348499Y1956550D03*
X347999Y1944550D03*
X347699Y1972250D03*
X345499Y1987550D03*
X364999Y4550D03*
X374499Y77550D03*
X363999Y136050D03*
Y121550D03*
Y153550D03*
X359399Y307250D03*
X368299Y386350D03*
X359399Y576050D03*
Y599650D03*
X360399Y615550D03*
X359699Y627550D03*
X358899Y657150D03*
X359399Y669450D03*
X359199Y690650D03*
X377499Y1182050D03*
Y1210050D03*
Y1201050D03*
X376499Y1236550D03*
Y1255550D03*
Y1264550D03*
X376599Y1293950D03*
X375599Y1323350D03*
X374499Y1347550D03*
Y1375550D03*
Y1366550D03*
X373499Y1402050D03*
Y1421050D03*
X376299Y1437650D03*
X373499Y1430050D03*
X373099Y1456550D03*
X374799Y1491250D03*
X374099Y1554550D03*
X376099Y1572850D03*
X375099Y1608250D03*
X377700Y1629000D03*
X374999Y1656750D03*
X377099Y1696350D03*
X359499Y1736850D03*
X376799Y1734050D03*
X376499Y1775550D03*
X369499Y1855950D03*
X359999Y1878550D03*
X369799Y1880050D03*
X359999Y1897550D03*
Y1906550D03*
X369999Y1901950D03*
X358999Y1925050D03*
X369199Y1919750D03*
X367299Y1956950D03*
X367999Y1940250D03*
X367299Y1972950D03*
X364999Y1987050D03*
X382499Y5050D03*
X395999Y5550D03*
X398799Y36152D03*
X381999Y50150D03*
X382339Y41610D03*
X389599Y90950D03*
X385999Y78050D03*
X380599Y103550D03*
X381299Y136750D03*
X400499Y134050D03*
Y119550D03*
Y151550D03*
X389299Y161650D03*
X387599Y220150D03*
X385999Y207250D03*
X382999Y276650D03*
X386899Y299250D03*
X383299Y310250D03*
X386599Y348450D03*
X394899Y357750D03*
X380599Y381050D03*
X380099Y1709650D03*
X393499Y1759550D03*
X393999Y1784550D03*
X387899Y1802850D03*
X391499Y1855950D03*
X389499Y1885050D03*
Y1913050D03*
Y1904050D03*
X388499Y1932950D03*
Y1950550D03*
X385099Y1975950D03*
X399299Y1976750D03*
X388499Y1959550D03*
X382499Y1987550D03*
X413499Y6050D03*
X416999Y25050D03*
X417499Y46550D03*
X416999Y63550D03*
X417499Y79050D03*
Y93550D03*
X401499Y80550D03*
X417499Y108050D03*
Y125550D03*
X416999Y145050D03*
Y164050D03*
X417999Y185050D03*
X412999Y275550D03*
Y307550D03*
Y290050D03*
X422199Y363350D03*
X420199Y391350D03*
X415099Y422550D03*
X410799Y431150D03*
X419599Y458550D03*
X420199Y638550D03*
X418799Y877050D03*
Y896050D03*
X409499Y1102550D03*
X419999Y1115550D03*
X415499Y1161550D03*
X416099Y1183550D03*
X415499Y1176050D03*
X419499Y1234050D03*
Y1219550D03*
X420099Y1241550D03*
X416699Y1342650D03*
X416199Y1367550D03*
X414799Y1532350D03*
X418299Y1561250D03*
X415999Y1603250D03*
X416199Y1625250D03*
X414799Y1653750D03*
X414399Y1678350D03*
X414499Y1707250D03*
X410757Y1772872D03*
X417799Y1790850D03*
X414499Y1810450D03*
X406999Y1855950D03*
X421399Y1888050D03*
X406499Y1893050D03*
Y1874050D03*
X421399Y1907050D03*
X406999Y1905050D03*
X420399Y1934550D03*
X421399Y1916050D03*
X405499Y1920550D03*
X420399Y1953550D03*
X405999Y1951550D03*
X405499Y1939550D03*
X420399Y1962550D03*
X420799Y1977250D03*
X420500Y1987000D03*
X403500D03*
X432999Y6050D03*
X436499Y31350D03*
Y50350D03*
X437499Y71350D03*
X441799Y102450D03*
Y121450D03*
X442799Y142450D03*
X430499Y217050D03*
X423799Y259750D03*
X437499Y275050D03*
Y307050D03*
Y289550D03*
X422499Y348150D03*
X426599Y415350D03*
X443199Y440850D03*
X440099Y459250D03*
X431099Y479350D03*
X430099Y551450D03*
X427999Y580050D03*
Y565550D03*
Y597550D03*
X427499Y624550D03*
X437299Y744650D03*
X435299Y763150D03*
X424999Y766550D03*
X435299Y777650D03*
X422999Y785050D03*
X434799Y814650D03*
X435299Y795150D03*
X422999Y799550D03*
X434799Y833650D03*
X422999Y817050D03*
X422499Y855550D03*
Y836550D03*
X442599Y905650D03*
Y924650D03*
X423299Y994050D03*
Y1013050D03*
X424299Y1034050D03*
X432599Y1064550D03*
X433599Y1085550D03*
X428999Y1102550D03*
X439499Y1115550D03*
X436999Y1128050D03*
X437599Y1150050D03*
X436999Y1142550D03*
X443199Y1224250D03*
Y1238750D03*
X424999Y1278550D03*
Y1259550D03*
X425499Y1290550D03*
X428499Y1325350D03*
X434499Y1360250D03*
X422299Y1394950D03*
X441499Y1399550D03*
X426799Y1416050D03*
X441499Y1414050D03*
X423299Y1430350D03*
X425799Y1447950D03*
X441499Y1431550D03*
X427099Y1469150D03*
X424299Y1541350D03*
X439599Y1552150D03*
X434500Y1579500D03*
X432499Y1617550D03*
X431999Y1605550D03*
X425499Y1635050D03*
X432400Y1680100D03*
X427499Y1662050D03*
X428600Y1691200D03*
X435300Y1715300D03*
X429499Y1748050D03*
X441499Y1758050D03*
X436799Y1772550D03*
X422999Y1778550D03*
X426499Y1855450D03*
X434299Y1876050D03*
Y1904050D03*
Y1895050D03*
X433299Y1922550D03*
Y1950550D03*
Y1941550D03*
X436299Y1977250D03*
X438999Y1987550D03*
X448499Y6050D03*
X445799Y165650D03*
Y184650D03*
X446799Y205650D03*
X449999Y217050D03*
X450300Y404200D03*
X453999Y417550D03*
X454999Y438550D03*
X454499Y472550D03*
Y458050D03*
Y490050D03*
X453999Y509550D03*
X452499Y579550D03*
Y565050D03*
Y597050D03*
X463999Y659550D03*
X450399Y672750D03*
X444799Y687350D03*
X463999Y674050D03*
Y691550D03*
X451099Y711650D03*
X452099Y762450D03*
Y781450D03*
X453399Y807950D03*
Y826950D03*
X462999Y865050D03*
Y884050D03*
X464499Y896050D03*
X462499Y914550D03*
Y929050D03*
X443599Y945650D03*
X462499Y946550D03*
X461999Y966050D03*
Y985050D03*
X462499Y1043850D03*
Y1062850D03*
X463499Y1083850D03*
X463999Y1102050D03*
X444499Y1102550D03*
X454999Y1115550D03*
X453499Y1140550D03*
X454499Y1161550D03*
X443799Y1246250D03*
Y1274250D03*
Y1265250D03*
X448099Y1341250D03*
X444899Y1377950D03*
X464199Y1401450D03*
X459999Y1424050D03*
X456399Y1445950D03*
X459699Y1468050D03*
X445099Y1464250D03*
X444299Y1532650D03*
X461399Y1541650D03*
X452199Y1550650D03*
X449199Y1579050D03*
X443799Y1612250D03*
X460199Y1632850D03*
X449599Y1656950D03*
X448399Y1699450D03*
X447699Y1682850D03*
X458499Y1742050D03*
X463999Y1772050D03*
X445499Y1792550D03*
X448099Y1809450D03*
X443999Y1855950D03*
X460299Y1892350D03*
X446999Y1880050D03*
X460299Y1911350D03*
X446999Y1908050D03*
Y1899050D03*
X460299Y1920350D03*
X445999Y1926550D03*
X459299Y1938850D03*
X445999Y1954550D03*
Y1945550D03*
X459299Y1966850D03*
Y1957850D03*
X455799Y1976750D03*
X456500Y1987500D03*
X467999Y5550D03*
X485499Y6050D03*
X465799Y24750D03*
Y43750D03*
X466799Y64750D03*
X470399Y84550D03*
Y103550D03*
X471399Y124550D03*
X473099Y141050D03*
X483599Y179350D03*
X473099Y160050D03*
X474099Y181050D03*
X472999Y214550D03*
X466399Y304950D03*
X479299Y297250D03*
X468799Y414250D03*
X472499Y458050D03*
X471499Y493950D03*
X485299Y534550D03*
X479999Y581050D03*
Y566550D03*
Y598550D03*
X472999Y736550D03*
X467699Y772750D03*
X468699Y788350D03*
X479599Y847550D03*
X475699Y880450D03*
X483499Y1064850D03*
X484499Y1085850D03*
X481499Y1102550D03*
X474499Y1115050D03*
X473099Y1144550D03*
X474099Y1165550D03*
X465499Y1265550D03*
Y1284550D03*
Y1293550D03*
X468999Y1323950D03*
X473999Y1342450D03*
X468699Y1362850D03*
X485599Y1367550D03*
X466699Y1378150D03*
X481499Y1402550D03*
Y1417050D03*
X482599Y1449950D03*
X478299Y1464850D03*
X466999Y1530650D03*
X474299Y1544750D03*
X472299Y1572050D03*
X484200Y1579900D03*
X465999Y1603450D03*
X472499Y1611550D03*
X484999Y1636550D03*
X472499Y1620550D03*
X483599Y1662550D03*
X467999Y1668050D03*
X485599Y1694850D03*
X467999Y1687050D03*
Y1696050D03*
X468499Y1712550D03*
X480999Y1756050D03*
X484999Y1779050D03*
X472699Y1792150D03*
X481299Y1811150D03*
X480499Y1855450D03*
X464999D03*
X476199Y1877450D03*
Y1905450D03*
Y1896450D03*
X475199Y1923950D03*
Y1951950D03*
Y1942950D03*
X473299Y1977250D03*
X476000Y1987000D03*
X498999Y6050D03*
X499999Y25550D03*
X500499Y47050D03*
X499999Y64050D03*
X500499Y79550D03*
Y94050D03*
Y108550D03*
Y126050D03*
X499999Y145550D03*
Y164550D03*
X504199Y193250D03*
X502899Y217150D03*
X490999Y412550D03*
X503699Y419250D03*
X490999Y427050D03*
Y444550D03*
X498399Y470050D03*
X490499Y464050D03*
Y483050D03*
X491499Y504050D03*
X504499Y580550D03*
Y566050D03*
Y598050D03*
X488499Y659050D03*
Y673550D03*
Y691050D03*
X506599Y711650D03*
X487299Y716950D03*
X490299Y734550D03*
X489599Y752450D03*
X495999Y795050D03*
X493999Y813550D03*
Y828050D03*
Y845550D03*
X493499Y865050D03*
Y884050D03*
X485799Y920050D03*
Y901050D03*
X486799Y941050D03*
X493099Y996350D03*
X494099Y1017350D03*
X501499Y1102550D03*
X491999Y1115550D03*
X504399Y1132250D03*
X505399Y1153250D03*
X486499Y1210550D03*
Y1196050D03*
X506599Y1202350D03*
Y1216850D03*
X487099Y1218050D03*
X498299Y1323350D03*
X499199Y1350550D03*
X498899Y1386450D03*
Y1408350D03*
X500899Y1434350D03*
X505899Y1466250D03*
X488299Y1531050D03*
X499699Y1538950D03*
X502199Y1566250D03*
X487099Y1606250D03*
X501399Y1634550D03*
X502899Y1709650D03*
X496999Y1799550D03*
X499999Y1854950D03*
X505799Y1893050D03*
X492999Y1878050D03*
X505799Y1912050D03*
X493499Y1909050D03*
X492999Y1897050D03*
X505799Y1921050D03*
X491999Y1924550D03*
X504799Y1939550D03*
X492499Y1955550D03*
X491999Y1943550D03*
X504799Y1967550D03*
Y1958550D03*
X493799Y1977250D03*
X492500Y1987500D03*
X516499Y6550D03*
X522899Y45350D03*
Y64350D03*
X523899Y85350D03*
X520299Y122450D03*
Y141450D03*
X521299Y162450D03*
X516899Y306950D03*
X518999Y416550D03*
X511299Y449150D03*
X519499Y471550D03*
Y489050D03*
X508699Y498950D03*
X518999Y508550D03*
X509999Y640550D03*
Y655050D03*
Y672550D03*
X527499Y747150D03*
X525499Y772450D03*
X511199Y782050D03*
X512899Y823550D03*
X526499Y851150D03*
X512899Y842550D03*
X510899Y868150D03*
X522499Y876050D03*
X521999Y895550D03*
X506899Y919950D03*
Y900950D03*
X521999Y914550D03*
X516499Y957050D03*
X514499Y975550D03*
Y990050D03*
Y1007550D03*
X513999Y1046050D03*
Y1027050D03*
X518999Y1103050D03*
X511999Y1115550D03*
X527499Y1181550D03*
X527999Y1212550D03*
X527499Y1200550D03*
X507199Y1224350D03*
X525999Y1231050D03*
X507199Y1252350D03*
Y1243350D03*
X525999Y1245550D03*
X527499Y1278150D03*
X525999Y1263050D03*
X518499Y1346950D03*
X523499Y1360050D03*
X508599Y1370550D03*
X523499Y1379050D03*
X523999Y1391050D03*
X516999Y1418050D03*
Y1437050D03*
X517499Y1449050D03*
X518899Y1530150D03*
X510100Y1579800D03*
X508199Y1610450D03*
X518499Y1643950D03*
X509199Y1660550D03*
X507399Y1683350D03*
X522300Y1739200D03*
X508200Y1758200D03*
X515499Y1779050D03*
X526499Y1801150D03*
X514199Y1815750D03*
X517499Y1855450D03*
X519399Y1876750D03*
Y1904750D03*
Y1895750D03*
X518399Y1923250D03*
Y1951250D03*
Y1942250D03*
X509299Y1977250D03*
X511999Y1987550D03*
X535999Y6550D03*
X541499Y25050D03*
X541999Y46550D03*
X541499Y63550D03*
X541999Y79050D03*
Y93550D03*
Y108050D03*
Y125550D03*
X541499Y145050D03*
Y164050D03*
X528799Y199950D03*
X542499Y185050D03*
X533499Y217550D03*
X544799Y293950D03*
X540099Y306550D03*
X538799Y445050D03*
X539799Y466050D03*
X539299Y485550D03*
X534499Y640050D03*
Y654550D03*
Y672050D03*
X547999Y728550D03*
Y743050D03*
Y760550D03*
X547499Y780050D03*
X534499Y805950D03*
X547499Y799050D03*
X541399Y854450D03*
Y873450D03*
X539299Y935850D03*
X540299Y956850D03*
X540899Y981450D03*
Y1000450D03*
X541899Y1021450D03*
X534599Y1048550D03*
X535599Y1069550D03*
X538499Y1103050D03*
X548999Y1116050D03*
X529499D03*
X546499Y1180750D03*
Y1195250D03*
X547099Y1202750D03*
Y1230750D03*
Y1221750D03*
X548799Y1252850D03*
Y1267350D03*
X530499Y1297050D03*
X545099Y1355250D03*
X540399Y1382150D03*
X538799Y1409750D03*
X536799Y1436350D03*
X528499Y1460250D03*
X546099Y1467550D03*
X538999Y1528350D03*
X529799Y1555050D03*
X533800Y1575500D03*
X529499Y1616550D03*
X528999Y1604550D03*
X532499Y1635550D03*
X532599Y1655650D03*
X532499Y1669550D03*
Y1688550D03*
X532999Y1700550D03*
X538299Y1721050D03*
X532499Y1763050D03*
X539499Y1788150D03*
X531799Y1818450D03*
X538999Y1855950D03*
X547999Y1892350D03*
X533499Y1884050D03*
X547999Y1911350D03*
X533499Y1912050D03*
Y1903050D03*
X547999Y1920350D03*
X532499Y1930550D03*
X546999Y1938850D03*
X532499Y1949550D03*
X546999Y1966850D03*
Y1957850D03*
X546299Y1977250D03*
X528799Y1976750D03*
X532499Y1958550D03*
X531500Y1987500D03*
X551499Y6550D03*
X568099Y72550D03*
Y91550D03*
X569099Y112550D03*
X562799Y127750D03*
Y146750D03*
X563799Y167750D03*
X565999Y199950D03*
X568499Y217550D03*
X552999D03*
X555999Y412550D03*
X556499Y467550D03*
Y485050D03*
X555999Y504550D03*
X565699Y710650D03*
X549999Y710050D03*
X562999Y898050D03*
X560999Y916550D03*
Y931050D03*
Y948550D03*
X560499Y968050D03*
Y987050D03*
X560999Y999050D03*
X558999Y1017550D03*
Y1032050D03*
X558499Y1069050D03*
X558999Y1049550D03*
X558499Y1088050D03*
X568499Y1101550D03*
X553999Y1103050D03*
X564499Y1116050D03*
X567999Y1187550D03*
Y1215550D03*
Y1206550D03*
X565999Y1234050D03*
Y1248550D03*
X566399Y1273850D03*
X549399Y1274850D03*
X561099Y1301050D03*
X549399Y1293850D03*
Y1302850D03*
X555699Y1322950D03*
X559099Y1343250D03*
X557499Y1424050D03*
Y1443050D03*
Y1452050D03*
X567999Y1549950D03*
X552199Y1576650D03*
X552099Y1601950D03*
X569499Y1610550D03*
X553399Y1624550D03*
X569499Y1619550D03*
X554199Y1651950D03*
X555199Y1674750D03*
X555399Y1689350D03*
X555899Y1706750D03*
X556199Y1727050D03*
X560399Y1792550D03*
X555500Y1802700D03*
X554499Y1855950D03*
X562599Y1893450D03*
Y1874450D03*
Y1902450D03*
X561599Y1920950D03*
Y1948950D03*
Y1939950D03*
X570299Y1976250D03*
X568999Y1987050D03*
X553499D03*
X570999Y6050D03*
X588499Y6550D03*
X587999Y25050D03*
X588499Y46550D03*
X587999Y63550D03*
X588499Y125550D03*
X587999Y145050D03*
Y164050D03*
X588999Y185050D03*
X587999Y217050D03*
X572999Y255050D03*
Y269550D03*
Y287050D03*
X572499Y306550D03*
Y325550D03*
X573499Y346550D03*
X579899Y375750D03*
X577399Y420050D03*
X578399Y441050D03*
X577899Y460550D03*
X576099Y481850D03*
X577099Y502850D03*
X576599Y522350D03*
X573499Y658550D03*
Y673050D03*
Y690550D03*
X586299Y711250D03*
X577999Y732050D03*
X575999Y750550D03*
Y765050D03*
Y782550D03*
X575499Y802050D03*
Y821050D03*
X576499Y842050D03*
X578299Y895650D03*
Y914650D03*
X583299Y961450D03*
X570899Y946850D03*
X583299Y980450D03*
X570899Y965850D03*
X571899Y986850D03*
X573499Y1036550D03*
Y1055550D03*
X574499Y1076550D03*
X588499Y1101550D03*
X578999Y1114550D03*
X582699Y1233250D03*
X583299Y1255250D03*
X582699Y1247750D03*
X583299Y1274250D03*
X579299Y1300750D03*
X583299Y1283250D03*
X581999Y1370150D03*
X580999Y1412750D03*
X575699Y1438950D03*
X582999Y1461250D03*
X590599Y1483450D03*
X582299Y1534150D03*
X588099Y1572050D03*
X573400Y1577600D03*
X588000Y1604000D03*
X590799Y1627850D03*
X580799Y1646150D03*
X572999Y1675550D03*
X590599Y1694450D03*
X572999Y1694550D03*
Y1703550D03*
X580299Y1722550D03*
X582599Y1740050D03*
X573999Y1855450D03*
X588899Y1882350D03*
X575999Y1888050D03*
X588899Y1910350D03*
Y1901350D03*
X575999Y1907050D03*
X587899Y1928850D03*
X576499Y1919050D03*
X574999Y1934550D03*
X587899Y1956850D03*
Y1947850D03*
X574999Y1953550D03*
X585799Y1976250D03*
X575499Y1965550D03*
X588499Y1986550D03*
X608499Y6550D03*
X603999Y35350D03*
Y54350D03*
X604999Y75350D03*
X603999Y133750D03*
Y152750D03*
X604999Y173750D03*
X605499Y217550D03*
X599299Y344650D03*
X600299Y365650D03*
X599799Y385150D03*
X607399Y380250D03*
X592999Y407550D03*
Y422050D03*
Y439550D03*
X592499Y459050D03*
Y478050D03*
X593499Y499050D03*
X595999Y624050D03*
Y609550D03*
Y641550D03*
X605299Y661750D03*
X609499Y708050D03*
X597999Y690050D03*
X607499Y726550D03*
Y741050D03*
Y758550D03*
X606999Y778050D03*
Y797050D03*
X603499Y904050D03*
X601499Y922550D03*
Y937050D03*
Y954550D03*
X600999Y1002050D03*
X611399Y1026650D03*
X598999Y1020550D03*
X611399Y1045650D03*
X598999Y1035050D03*
X612399Y1066650D03*
X598999Y1052550D03*
X598499Y1072050D03*
X605999Y1102050D03*
X598499Y1091050D03*
X598999Y1114550D03*
X603899Y1157850D03*
X597599Y1196050D03*
X596599Y1215050D03*
X600899Y1238650D03*
X598499Y1280550D03*
Y1261550D03*
X598999Y1292550D03*
X608899Y1305050D03*
X605599Y1326350D03*
X606199Y1338250D03*
X599499Y1351550D03*
X599999Y1382550D03*
X599499Y1370550D03*
X604899Y1407750D03*
X601299Y1447650D03*
X610899Y1496750D03*
X599799Y1544650D03*
X611900Y1577900D03*
X612499Y1615550D03*
X611999Y1603550D03*
X600599Y1645450D03*
X593399Y1668850D03*
X609499Y1675050D03*
Y1692050D03*
X607599Y1716450D03*
X606999Y1745550D03*
X593299Y1760950D03*
X608599Y1810750D03*
X595199Y1820910D03*
X611999Y1855950D03*
X591499D03*
X602799Y1887350D03*
Y1906350D03*
X601799Y1933850D03*
X602799Y1915350D03*
X601799Y1952850D03*
Y1961850D03*
X605299Y1975750D03*
X605999Y1987050D03*
X625999Y7050D03*
X624499Y23050D03*
X624999Y44550D03*
X624499Y61550D03*
X624999Y123550D03*
X624499Y143050D03*
Y162050D03*
X625499Y183050D03*
X623899Y202550D03*
X625499Y217550D03*
X627999Y262550D03*
Y248050D03*
Y280050D03*
X627499Y299550D03*
X628200Y320000D03*
X628499Y339550D03*
X632399Y358750D03*
X620999Y411550D03*
X621999Y432550D03*
X621499Y452050D03*
Y466550D03*
Y484050D03*
X613700Y504600D03*
X620499Y623550D03*
Y609050D03*
X631999Y639650D03*
X622999Y672050D03*
Y689550D03*
X629099Y714050D03*
X633499Y750150D03*
X621499Y767150D03*
X621999Y835050D03*
X612999Y854550D03*
X629499Y853050D03*
Y868550D03*
X613499Y868050D03*
X616699Y948250D03*
Y967250D03*
X617699Y988250D03*
X631999Y1001550D03*
X629999Y1020050D03*
Y1034550D03*
Y1052050D03*
X629499Y1071550D03*
Y1090550D03*
X616499Y1115050D03*
X627699Y1143550D03*
X628699Y1164550D03*
X626199Y1183450D03*
X630499Y1243950D03*
X617599Y1246250D03*
X618199Y1268250D03*
X617599Y1260750D03*
X618199Y1296250D03*
Y1287250D03*
X631799Y1322650D03*
X617899Y1360850D03*
X632499Y1347950D03*
X625499Y1383450D03*
X627499Y1406050D03*
X626799Y1432350D03*
X625199Y1489150D03*
X617699Y1530350D03*
X623499Y1564050D03*
X633499Y1615450D03*
X628499Y1636650D03*
X627299Y1659550D03*
X625499Y1725050D03*
X619499Y1803150D03*
X627273Y1793905D03*
X626999Y1800050D03*
X632799Y1820450D03*
X627494Y1829068D03*
X627499Y1855950D03*
X630699Y1872750D03*
Y1891750D03*
Y1900750D03*
X616499Y1913050D03*
Y1894050D03*
X629699Y1919250D03*
X616499Y1922050D03*
X629699Y1947250D03*
Y1938250D03*
X615499Y1940550D03*
X622799Y1976250D03*
X615499Y1959550D03*
Y1968550D03*
X626999Y1987050D03*
X645499Y7050D03*
X651799Y40650D03*
Y59650D03*
X652799Y80650D03*
X649899Y138350D03*
Y157350D03*
X650899Y178350D03*
X642999Y218050D03*
X653999Y286550D03*
X635399Y376250D03*
X643599Y395950D03*
X644599Y416950D03*
X644099Y450950D03*
Y436450D03*
X642499Y525750D03*
X643499Y546750D03*
X642999Y566250D03*
X640599Y604650D03*
X645099Y639150D03*
X647499Y657050D03*
Y671550D03*
X648999Y702350D03*
X647499Y689050D03*
X651999Y718350D03*
X647399Y742150D03*
X653099Y803350D03*
X645799Y816650D03*
X641599Y843250D03*
Y862250D03*
X642599Y883250D03*
X639499Y952150D03*
Y971150D03*
X633999Y1103050D03*
X641799Y1137650D03*
X650299Y1153150D03*
X651299Y1174150D03*
X650599Y1182050D03*
X651599Y1203050D03*
X638999Y1267550D03*
Y1286550D03*
Y1295550D03*
X654499Y1354050D03*
Y1373050D03*
X652999Y1403550D03*
Y1418050D03*
Y1435550D03*
X636799Y1461250D03*
X643099Y1541350D03*
X652399Y1575850D03*
X639200Y1576200D03*
X635500Y1603900D03*
X652499Y1618550D03*
Y1609550D03*
X649399Y1644950D03*
X635099Y1691150D03*
X642499Y1709050D03*
X650399Y1771250D03*
X642400Y1800100D03*
X640999Y1815550D03*
X644049Y1810834D03*
X645099Y1877550D03*
X645399Y1906150D03*
X646799Y1926450D03*
X644999Y1934050D03*
Y1953050D03*
X643799Y1976250D03*
X645499Y1965050D03*
X642499Y1987050D03*
X660999Y7050D03*
X674999Y20550D03*
X675499Y42050D03*
Y74550D03*
X674999Y59050D03*
X675499Y89050D03*
Y103550D03*
Y121050D03*
X674999Y140550D03*
Y159550D03*
X675999Y180550D03*
X662499Y218050D03*
X656499Y307050D03*
Y324550D03*
X655999Y344050D03*
X659899Y363250D03*
X666999Y476550D03*
Y491050D03*
Y508550D03*
X666499Y528050D03*
Y547050D03*
X667499Y568050D03*
X665999Y623550D03*
X673999Y645150D03*
X665499Y766550D03*
X664999Y786050D03*
Y805050D03*
X665999Y826050D03*
X663999Y844550D03*
Y876550D03*
Y859050D03*
X663499Y896050D03*
Y915050D03*
X664499Y936050D03*
X658999Y959050D03*
X656999Y977550D03*
Y992050D03*
X673999Y1017550D03*
X656999Y1009550D03*
X673999Y1036550D03*
X656499Y1029050D03*
X674699Y1061450D03*
X656499Y1048050D03*
X674699Y1080450D03*
X669499Y1116550D03*
X674999Y1134950D03*
X667199Y1152850D03*
X668199Y1173850D03*
X670199Y1192750D03*
X671199Y1213750D03*
X668699Y1227650D03*
X657099Y1272850D03*
X657799Y1288450D03*
X672999Y1303450D03*
X656399Y1307050D03*
X671999Y1324950D03*
X665699Y1337250D03*
X654999Y1385050D03*
X659699Y1445950D03*
X665699Y1462250D03*
X656099Y1479550D03*
X672399Y1508750D03*
X673699Y1535350D03*
X662099Y1549650D03*
X670699Y1603150D03*
X671399Y1625350D03*
X657099Y1668850D03*
X674999Y1676550D03*
X656499Y1697050D03*
X675499Y1738050D03*
X665399Y1752350D03*
X675499Y1757050D03*
X675999Y1769050D03*
X659159Y1792278D03*
X659549Y1815384D03*
Y1810634D03*
X667999Y1870950D03*
X669399Y1855350D03*
X674899Y1892350D03*
X661299Y1890050D03*
X674899Y1911350D03*
X661299Y1909050D03*
X674899Y1920350D03*
X661299Y1918050D03*
X673899Y1938850D03*
X660299Y1936550D03*
Y1955550D03*
X673899Y1966850D03*
Y1957850D03*
X660299Y1964550D03*
X659299Y1976250D03*
X661999Y1986550D03*
X680499Y6550D03*
X694999Y62650D03*
Y81650D03*
X695999Y102650D03*
X688999Y196550D03*
X677999Y218050D03*
X683499Y263050D03*
Y248550D03*
X680500Y280700D03*
X682999Y300050D03*
Y319050D03*
X683999Y340050D03*
X694999Y480550D03*
X695999Y501550D03*
X695499Y521050D03*
X691399Y548350D03*
X692399Y569350D03*
X691899Y588850D03*
X690499Y623050D03*
X693999Y648150D03*
X678499Y671050D03*
X679299Y703050D03*
X678499Y688550D03*
X681899Y713650D03*
X696299Y741850D03*
X694599Y763450D03*
X685999Y780050D03*
X687099Y804650D03*
Y823650D03*
X688099Y844650D03*
X687099Y896350D03*
Y915350D03*
X688099Y936350D03*
X678299Y978350D03*
Y997350D03*
X694999Y993050D03*
X692999Y1011550D03*
Y1026050D03*
Y1043550D03*
X692499Y1063050D03*
Y1082050D03*
X689999Y1105550D03*
X695999Y1203050D03*
Y1235050D03*
Y1217550D03*
X684299Y1249550D03*
X695999Y1323350D03*
X677999Y1347550D03*
X694999Y1360050D03*
X680299Y1365850D03*
X694999Y1379050D03*
X681299Y1393150D03*
X692999Y1406550D03*
X694999Y1388050D03*
X678299Y1425050D03*
X692999Y1421050D03*
X686999Y1468850D03*
X685299Y1551950D03*
X681299Y1579150D03*
X693599Y1602450D03*
X686699Y1638650D03*
X691999Y1660550D03*
X693099Y1722350D03*
X690499Y1744950D03*
X694599Y1768450D03*
X690249Y1805634D03*
X693549Y1793134D03*
X686473Y1818375D03*
X686999Y1870250D03*
X690899Y1855850D03*
X696299Y1898850D03*
X676399Y1901150D03*
X695299Y1926450D03*
X685499Y1940050D03*
X696299Y1976250D03*
X678799Y1975750D03*
X685499Y1959050D03*
Y1968050D03*
X679499Y1987050D03*
X697999Y7050D03*
X712499Y6050D03*
X699699Y141750D03*
Y160750D03*
X700699Y181750D03*
X711999Y218050D03*
X711499Y252550D03*
X711999Y307550D03*
Y293050D03*
Y325050D03*
X711499Y344550D03*
X712699Y434450D03*
X713699Y455450D03*
X713199Y474950D03*
Y489450D03*
X712599Y521050D03*
X713599Y542050D03*
X713099Y561550D03*
X717099Y636050D03*
X702999Y656050D03*
Y688050D03*
Y670550D03*
X710899Y751150D03*
X716599Y736850D03*
X706999Y792550D03*
X707499Y773050D03*
X706999Y811550D03*
X707999Y832550D03*
X705999Y851050D03*
Y865550D03*
X707399Y899550D03*
Y918550D03*
X706499Y942550D03*
X713999Y1017050D03*
Y1031550D03*
X713499Y1068550D03*
X713999Y1049050D03*
X709999Y1105550D03*
X700499Y1118550D03*
X704299Y1132650D03*
X716999Y1148150D03*
X697499Y1153550D03*
X717999Y1169150D03*
X697499Y1172550D03*
X713399Y1178750D03*
X697999Y1184550D03*
X713599Y1214650D03*
X714399Y1199750D03*
X708699Y1243550D03*
X709699Y1264550D03*
X707899Y1346250D03*
X702299Y1404450D03*
X713899Y1386450D03*
X716899Y1459850D03*
X700899Y1450250D03*
X716199Y1503050D03*
X714599Y1533950D03*
X708899Y1549250D03*
X698599Y1568550D03*
X706700Y1579900D03*
X717099Y1702450D03*
X702599Y1730550D03*
X715999Y1744050D03*
X709099Y1751850D03*
X715999Y1763050D03*
Y1772050D03*
X706549Y1793634D03*
X705000Y1811900D03*
X711500Y1817700D03*
X704300Y1828400D03*
X697999Y1844550D03*
X706399Y1855850D03*
X705599Y1891850D03*
X716599Y1918450D03*
X698299Y1948050D03*
X711899Y1944050D03*
X709199Y1962950D03*
X717999Y1987550D03*
X702499D03*
X729999Y6550D03*
X725499Y23550D03*
X725999Y45050D03*
X725499Y62050D03*
X725999Y77550D03*
Y92050D03*
Y106550D03*
X738199Y137450D03*
X725999Y124050D03*
X725499Y143550D03*
Y162550D03*
X726499Y183550D03*
X728899Y204550D03*
X729499Y218550D03*
X723200Y275500D03*
X737999Y467050D03*
X738999Y488050D03*
X738499Y507550D03*
Y539550D03*
Y522050D03*
X737999Y559050D03*
X731499Y572050D03*
Y586550D03*
Y604050D03*
X729699Y640350D03*
X723499Y654850D03*
X739399Y688150D03*
X720899Y712250D03*
X732499Y729250D03*
X727099Y715050D03*
X733799Y761450D03*
X723999Y783350D03*
Y802350D03*
X724999Y823350D03*
X728499Y841850D03*
X729999Y862850D03*
Y881850D03*
X730999Y902850D03*
X723699Y936250D03*
Y955250D03*
X724699Y976250D03*
X734999Y1030550D03*
Y1045050D03*
Y1062550D03*
X727499Y1106050D03*
X737999Y1119050D03*
X720499Y1118550D03*
X727499Y1132650D03*
X737999Y1159550D03*
Y1187550D03*
Y1178550D03*
X735999Y1206050D03*
X725499Y1231650D03*
X735999Y1220550D03*
X725499Y1250650D03*
X723499Y1278150D03*
X725499Y1259650D03*
X723499Y1292650D03*
X719199Y1322350D03*
X739199Y1348950D03*
X734199Y1373850D03*
X736199Y1399050D03*
X737799Y1428350D03*
X721899Y1419050D03*
X719499Y1446650D03*
X729199Y1492750D03*
X735799Y1533650D03*
X734499Y1563550D03*
X722199Y1564250D03*
X719999Y1605050D03*
X732999Y1620050D03*
X738799Y1677250D03*
X727399Y1694350D03*
X739199Y1716750D03*
X721199Y1723750D03*
X729999Y1756450D03*
X729499Y1778750D03*
X728099Y1844750D03*
X723199Y1867950D03*
X725899Y1855350D03*
X732999Y1868550D03*
X728299Y1888850D03*
X732199Y1878750D03*
X728799Y1908150D03*
Y1933050D03*
X736799Y1919450D03*
X730499Y1954650D03*
X721499Y1974550D03*
X737499Y1987050D03*
X749499Y6550D03*
X751499Y48350D03*
X757499Y44050D03*
Y63050D03*
X758499Y84050D03*
X752099Y112150D03*
X749499Y218550D03*
X749899Y398550D03*
X750899Y419550D03*
X750399Y453550D03*
Y439050D03*
X755199Y488150D03*
X756199Y509150D03*
X755699Y528650D03*
X754499Y564650D03*
X755499Y585650D03*
X754999Y605150D03*
X747999Y670750D03*
X754999Y694050D03*
X749999Y700050D03*
X752999Y746842D03*
X757499Y745342D03*
X749799Y767450D03*
X743099Y785350D03*
X751999Y817050D03*
X751499Y855550D03*
Y836550D03*
X751599Y887350D03*
Y906350D03*
X752599Y927350D03*
X749999Y946550D03*
Y965550D03*
X751399Y1004550D03*
X750999Y986550D03*
X751399Y1023550D03*
X752399Y1052550D03*
X753999Y1100050D03*
X755600Y1149800D03*
X758799Y1171150D03*
Y1190150D03*
Y1199150D03*
X756799Y1232150D03*
Y1217650D03*
X757399Y1258650D03*
Y1239650D03*
X740499Y1252550D03*
X757399Y1267650D03*
X740499Y1270050D03*
X740799Y1298750D03*
X755399Y1300650D03*
Y1286150D03*
X742099Y1320650D03*
X758499Y1371050D03*
X754999Y1420050D03*
Y1437550D03*
X741099Y1450250D03*
Y1498150D03*
X747199Y1509150D03*
X755499Y1507550D03*
X758199Y1553650D03*
X755499Y1568550D03*
X743400Y1578700D03*
X751300Y1604900D03*
X756299Y1679050D03*
X750099Y1694950D03*
X756499Y1712150D03*
X747499Y1734350D03*
X751899Y1752150D03*
X747799Y1766750D03*
X744049Y1791634D03*
X740549Y1802634D03*
X753949Y1798194D03*
X755000Y1825000D03*
X740549Y1810384D03*
X747599Y1844250D03*
X744699Y1868450D03*
X758399Y1868350D03*
X743399Y1855850D03*
X743799Y1888850D03*
X753699Y1879250D03*
X755299Y1902150D03*
X739799D03*
X755500Y1914500D03*
X746499Y1974250D03*
X759114Y1957673D03*
X754999Y1987550D03*
X764999Y6550D03*
X763399Y24150D03*
X774399Y54050D03*
X775399Y80250D03*
X778399Y105250D03*
X767399Y140150D03*
X760799Y181950D03*
X779399Y200550D03*
X766999Y219050D03*
X770999Y302050D03*
Y290050D03*
Y295550D03*
X763571Y295622D03*
X777999Y296050D03*
X760778Y345050D03*
X768178Y333964D03*
X774999Y476550D03*
Y462050D03*
Y494050D03*
X774499Y513550D03*
Y532550D03*
X775499Y553550D03*
X764599Y655750D03*
X766499Y699050D03*
Y705550D03*
Y732842D03*
X762999Y734550D03*
X778999Y806950D03*
X763099Y796350D03*
X775199Y839250D03*
Y858250D03*
X776199Y879250D03*
X772199Y920650D03*
Y939650D03*
X773199Y960650D03*
X776899Y988050D03*
Y1007050D03*
X777899Y1028050D03*
X760999Y1095550D03*
X773499Y1101050D03*
X769499D03*
X773499Y1105050D03*
X769499D03*
X767083Y1134550D03*
X768199Y1138590D03*
X762499Y1335550D03*
X779399Y1361850D03*
X762499Y1353050D03*
X773999Y1393450D03*
X763399Y1401450D03*
X769300Y1488100D03*
X779000Y1488400D03*
X771399Y1474550D03*
X770999Y1500050D03*
X780499D03*
X773499Y1509050D03*
X769499D03*
X771225Y1539474D03*
X767936Y1540336D03*
X768500Y1577500D03*
X776999Y1647650D03*
X765099Y1664950D03*
X770399Y1699650D03*
X779999Y1717050D03*
X770099Y1730350D03*
X779899Y1748150D03*
X765600Y1756800D03*
X774500Y1788000D03*
X770999Y1820550D03*
X765099Y1844750D03*
X779699Y1867950D03*
X779399Y1855850D03*
X763899D03*
X780799Y1888850D03*
X763299Y1888350D03*
X769199Y1879250D03*
X774499Y1908050D03*
X765999D03*
X775999Y1916050D03*
X768499Y1917550D03*
X767999Y1945173D03*
X764908Y1946592D03*
X777499Y1987550D03*
X784499Y6050D03*
X801999Y6550D03*
X796999Y27050D03*
X797499Y48550D03*
X796999Y65550D03*
X797499Y81050D03*
Y95550D03*
Y110050D03*
X796599Y123450D03*
X797499Y127550D03*
X796999Y147050D03*
Y166050D03*
X797999Y187050D03*
X786499Y219050D03*
X800999Y216550D03*
X785499Y291050D03*
X786978Y298529D03*
X784499Y334050D03*
X789999Y570050D03*
Y602050D03*
Y584550D03*
X782999Y699550D03*
X784939Y733550D03*
X802499Y814550D03*
X801999Y834050D03*
Y853050D03*
X800999Y892550D03*
Y907050D03*
Y924550D03*
X800499Y944050D03*
Y963050D03*
X801499Y984050D03*
X800999Y1005550D03*
Y1020050D03*
Y1037550D03*
X783999Y1096550D03*
X789499Y1099550D03*
X784439Y1136550D03*
X790999Y1194550D03*
Y1175550D03*
X791499Y1206550D03*
X789499Y1225050D03*
Y1257050D03*
Y1239550D03*
X788999Y1278150D03*
X791999Y1294450D03*
X795299Y1326650D03*
X799999Y1340550D03*
X798299Y1344250D03*
X799999Y1358050D03*
X781999Y1434650D03*
X786500Y1488600D03*
X801300Y1489000D03*
X786999Y1506550D03*
X784577Y1535628D03*
X797299Y1646650D03*
X802899Y1670550D03*
X782999Y1668050D03*
Y1687050D03*
X783499Y1699050D03*
X794499Y1734550D03*
X787900Y1758800D03*
X788000Y1788000D03*
X791999Y1819050D03*
X783499Y1827050D03*
X801099Y1844750D03*
X785599D03*
X791799Y1855850D03*
X797199Y1868450D03*
X788699Y1878750D03*
X783499Y1907050D03*
X790499Y1913050D03*
X785939Y1946800D03*
X789299Y1983850D03*
X792999Y1987550D03*
X818999Y6050D03*
X817599Y43750D03*
X813299Y49350D03*
Y68350D03*
X814299Y89350D03*
X813299Y110850D03*
X821199Y137450D03*
X805899Y126150D03*
X820749Y163850D03*
X813249Y163800D03*
X821999Y193116D03*
X819299Y413250D03*
Y394250D03*
X820299Y434250D03*
X802999Y466050D03*
X803999Y487050D03*
X803499Y506550D03*
Y538550D03*
Y521050D03*
X802999Y558050D03*
X814499Y569550D03*
Y601550D03*
Y584050D03*
X811499Y767550D03*
Y782050D03*
Y799550D03*
X802999Y874050D03*
X808299Y1175850D03*
X806599Y1189750D03*
X803599Y1211050D03*
X810199Y1229350D03*
Y1248350D03*
Y1257350D03*
X808199Y1275850D03*
Y1290350D03*
X822199Y1335250D03*
X819199Y1353550D03*
X806499Y1390550D03*
X803299Y1426650D03*
X806499Y1408050D03*
X805899Y1464250D03*
X813300Y1604100D03*
X803599Y1618350D03*
X814599Y1642650D03*
X823499Y1674050D03*
X808899Y1698450D03*
X823499Y1693050D03*
Y1702050D03*
X824100Y1719900D03*
X819400Y1721900D03*
X819200Y1727100D03*
X808299Y1755250D03*
X812000Y1799500D03*
X821249Y1791250D03*
X811000Y1793000D03*
X822499Y1815164D03*
X809299Y1856350D03*
X818900Y1870800D03*
X806199Y1879250D03*
X813599Y1979950D03*
X812499Y1987050D03*
X836499Y6550D03*
X824899Y25150D03*
X844799Y19850D03*
X841499Y135550D03*
X837499Y138550D03*
X838499Y145050D03*
X827499Y163550D03*
X839249Y164050D03*
X836500Y274950D03*
X827499Y313424D03*
X838499Y352050D03*
X839299Y390950D03*
Y409950D03*
X840299Y430950D03*
X824899Y500450D03*
X825899Y521450D03*
X825399Y540950D03*
X834599Y543050D03*
X835599Y564050D03*
X835099Y583550D03*
X835150Y677650D03*
X836149Y714050D03*
X835999Y767050D03*
X837799Y754150D03*
X835999Y781550D03*
Y799050D03*
X825199Y850850D03*
X827699Y873450D03*
Y892450D03*
X828699Y913450D03*
X826999Y963150D03*
Y982150D03*
X827999Y1003150D03*
X841999Y1118550D03*
X836149D03*
X839999Y1157550D03*
X831499Y1181550D03*
Y1209550D03*
Y1200550D03*
X829499Y1228050D03*
Y1242550D03*
X828199Y1267850D03*
X826199Y1294450D03*
X831499Y1324950D03*
X841999Y1341050D03*
Y1358550D03*
X825500Y1379000D03*
X834499Y1397550D03*
X836600Y1416500D03*
X836625Y1487400D03*
X843999Y1523550D03*
X839499D03*
X839899Y1562050D03*
X825999Y1578050D03*
X826499Y1609050D03*
X827199Y1622750D03*
X841499Y1638950D03*
X837199Y1660550D03*
X839199Y1683550D03*
X842799Y1701150D03*
X829200Y1719800D03*
X844499Y1788050D03*
X842500Y1799000D03*
X827999Y1791550D03*
X829799Y1856350D03*
X833199Y1868450D03*
X842199Y1879250D03*
X833100Y1878500D03*
X843999Y1928550D03*
X838999D03*
X840999Y1970550D03*
X829499Y1980250D03*
X829999Y1987550D03*
X855999Y6550D03*
X860799Y24150D03*
X853999Y132550D03*
X849999Y145550D03*
X861999Y146550D03*
X847450Y246666D03*
X850999Y246550D03*
X858478Y274050D03*
X858400Y352300D03*
X847999Y352550D03*
X854499Y387550D03*
Y373050D03*
Y405050D03*
X853999Y424550D03*
Y443550D03*
X854999Y464550D03*
X860199Y525050D03*
X861199Y546050D03*
X860699Y565550D03*
X861800Y591200D03*
X860499Y607550D03*
X851197Y652032D03*
X847493Y651981D03*
X860796Y678632D03*
X859999Y713050D03*
Y767550D03*
X856299Y753150D03*
X846799Y754150D03*
X865000Y752100D03*
X859999Y782050D03*
Y799550D03*
X847799Y828250D03*
X857099Y873450D03*
X866199Y920350D03*
Y901350D03*
X850999Y962550D03*
Y943550D03*
X851999Y983550D03*
X847355Y1058094D03*
X851042Y1058047D03*
X860133Y1084142D03*
X859999Y1118550D03*
X846499Y1170450D03*
X856400Y1157700D03*
X848999Y1158050D03*
X863300Y1153800D03*
X845799Y1190450D03*
X849799Y1199750D03*
X851999Y1237550D03*
Y1218550D03*
X852499Y1249550D03*
X850499Y1268050D03*
X860099Y1295450D03*
X850499Y1300050D03*
Y1282550D03*
X860799Y1358925D03*
X848861Y1462463D03*
X852429Y1462948D03*
X858827Y1485696D03*
X861999Y1522550D03*
X850099Y1572250D03*
X858400Y1561900D03*
X850499Y1562050D03*
X865300Y1557700D03*
X864000Y1578200D03*
X849900Y1605100D03*
X852499Y1621350D03*
X855799Y1658250D03*
X864099Y1683550D03*
X853799Y1790850D03*
X863099Y1813150D03*
X851500Y1821400D03*
X849375Y1824982D03*
X854905Y1825583D03*
X862499Y1823550D03*
X854977Y1818994D03*
X854480Y1867578D03*
X849999Y1867550D03*
X863788Y1866953D03*
X865501Y1858747D03*
X859314Y1891365D03*
X861414Y1928550D03*
X850499Y1977950D03*
X856999Y1970050D03*
X849999Y1970550D03*
X865200Y1968000D03*
X864999Y1987050D03*
X849499D03*
X871499Y6550D03*
X885999Y21150D03*
X872499Y133050D03*
X871499Y146050D03*
X882499Y147050D03*
X871786Y218924D03*
Y203924D03*
X874928Y238822D03*
X887400Y233555D03*
X871786Y233924D03*
X874790Y244748D03*
X887400Y259700D03*
X879878Y247724D03*
X871999Y283924D03*
X872136Y273924D03*
X886600Y303924D03*
X886200Y313924D03*
X870600Y346700D03*
X875799Y386250D03*
Y405250D03*
X876799Y426250D03*
X884399Y443450D03*
Y462450D03*
X885399Y483450D03*
X870719Y609705D03*
X870773Y624705D03*
X874999Y644550D03*
X870719Y639705D03*
X875270Y650059D03*
X887401Y665000D03*
X881125Y652050D03*
X871786Y679436D03*
Y709482D03*
X871499Y689436D03*
X871385Y719436D03*
X884499Y767050D03*
Y781550D03*
Y799050D03*
X873999Y830550D03*
Y845050D03*
Y862550D03*
X886999Y907350D03*
X867199Y941350D03*
X886999Y947250D03*
X870777Y1014948D03*
X870468Y1030227D03*
X886919Y1044478D03*
X870298Y1045227D03*
X874733Y1055792D03*
X874999Y1049550D03*
X880033Y1058592D03*
X887400Y1070600D03*
X872086Y1084948D03*
X871999Y1094948D03*
X871499Y1124948D03*
X872086Y1114948D03*
X871399Y1182850D03*
Y1201850D03*
Y1210850D03*
X869399Y1229350D03*
Y1243850D03*
X872099Y1268150D03*
X871399Y1291450D03*
X875399Y1322650D03*
X868499Y1392550D03*
Y1410050D03*
X871836Y1420460D03*
X886913Y1449010D03*
X871836Y1435460D03*
X874499Y1460550D03*
X874986Y1454983D03*
X879727Y1463696D03*
X871836Y1450460D03*
X887499Y1476050D03*
X872086Y1490460D03*
X871999Y1500460D03*
Y1520460D03*
X872086Y1530460D03*
X873099Y1572550D03*
X886900Y1604100D03*
X866499Y1603050D03*
Y1612050D03*
X868099Y1635650D03*
X887299Y1620050D03*
X877699Y1646650D03*
X882999Y1678250D03*
X866699Y1770950D03*
X879399Y1798150D03*
X869634Y1826876D03*
X871836Y1840972D03*
X887499Y1855550D03*
X869999Y1855972D03*
X887401Y1881500D03*
X871921Y1905972D03*
X871421Y1895972D03*
X872086Y1925972D03*
Y1935972D03*
X879399Y1974550D03*
X873399Y1963650D03*
X868699Y1983250D03*
X884499Y1986550D03*
X890999Y6050D03*
X908499Y6550D03*
X898999Y99050D03*
X889999Y132550D03*
X891999Y146050D03*
X896999Y141550D03*
X906999Y243150D03*
Y224150D03*
X907999Y264150D03*
X906399Y295250D03*
Y314250D03*
X907399Y335250D03*
X904999Y370550D03*
Y385050D03*
Y402550D03*
X904499Y422050D03*
Y441050D03*
X905499Y462050D03*
X898999Y622050D03*
Y604550D03*
X894000Y642400D03*
X900999Y652550D03*
Y670050D03*
X895999Y702550D03*
Y720050D03*
X898499Y830050D03*
Y844550D03*
X889699Y876050D03*
X898499Y862050D03*
X897299Y1182450D03*
X887999Y1209350D03*
X892499Y1224550D03*
Y1252550D03*
Y1243550D03*
X890499Y1271050D03*
Y1285550D03*
X890999Y1336550D03*
Y1354050D03*
X894499Y1423550D03*
Y1441050D03*
X895499Y1488050D03*
X902759Y1509585D03*
X894499Y1522050D03*
Y1539550D03*
X907500Y1604000D03*
X895999Y1661250D03*
X903599Y1686850D03*
X902900Y1709800D03*
X903299Y1814750D03*
X894999Y1829050D03*
X905299Y1852650D03*
X894000Y1868452D03*
X900299Y1876950D03*
X897299Y1904150D03*
X907599Y1930050D03*
X897599Y1938750D03*
X904299Y1954950D03*
X901999Y1987050D03*
X923999Y6050D03*
X920900Y54700D03*
X916499Y115050D03*
X913699Y484650D03*
Y503650D03*
X914699Y524650D03*
X922049Y574375D03*
X918999Y641550D03*
Y656050D03*
Y673550D03*
X918499Y693050D03*
Y712050D03*
X921899Y744850D03*
X919499Y733050D03*
X921899Y759350D03*
Y776850D03*
X921399Y796350D03*
X922399Y836350D03*
X921399Y815350D03*
X920399Y854850D03*
Y869350D03*
Y886850D03*
X919899Y906350D03*
Y925350D03*
X920899Y946350D03*
X922049Y978575D03*
X921499Y999050D03*
Y1013550D03*
Y1031050D03*
X920999Y1050550D03*
Y1069550D03*
X925499Y1103550D03*
X921999Y1090550D03*
X925499Y1118050D03*
Y1135550D03*
X924999Y1174050D03*
Y1155050D03*
X925999Y1195050D03*
Y1207050D03*
Y1221550D03*
Y1239050D03*
X925499Y1258550D03*
Y1277550D03*
X926499Y1298550D03*
X928499Y1325350D03*
X925999Y1365050D03*
Y1379550D03*
Y1397050D03*
X925499Y1416550D03*
Y1435550D03*
X926499Y1456550D03*
X924999Y1485550D03*
Y1471050D03*
Y1503050D03*
X914599Y1521650D03*
X924499Y1522550D03*
X910899Y1549250D03*
X924499Y1541550D03*
X909700Y1576400D03*
X925499Y1562550D03*
X925599Y1612050D03*
X923599Y1634350D03*
X908899Y1630050D03*
X914899Y1657550D03*
X922599Y1682150D03*
X911299Y1800850D03*
X921549Y1788475D03*
X928000Y1818500D03*
X922899Y1853650D03*
X914999Y1868050D03*
Y1887050D03*
X914899Y1912450D03*
X915499Y1899050D03*
X916599Y1942650D03*
X914899Y1972250D03*
X921499Y1986550D03*
X941499Y6550D03*
X946899Y122550D03*
X939199Y142050D03*
X939549Y175175D03*
X932499Y191550D03*
Y206050D03*
Y223550D03*
X931999Y243050D03*
Y262050D03*
X932999Y283050D03*
X933499Y304050D03*
Y318550D03*
Y336050D03*
X932999Y355550D03*
Y374550D03*
X933999Y395550D03*
X933499Y429550D03*
Y415050D03*
Y447050D03*
X932999Y466550D03*
Y485550D03*
X933999Y506550D03*
X935499Y539050D03*
Y524550D03*
Y556550D03*
X934999Y576050D03*
X950299Y599650D03*
X934999Y595050D03*
X950299Y614150D03*
X935999Y616050D03*
X950299Y631650D03*
X949799Y651150D03*
Y670150D03*
X950799Y691150D03*
X944499Y750050D03*
Y735550D03*
Y767550D03*
X943999Y787050D03*
Y806050D03*
X944999Y827050D03*
X942999Y845550D03*
Y877550D03*
Y860050D03*
X942499Y897050D03*
Y916050D03*
X943499Y937050D03*
X949299Y977450D03*
Y991950D03*
Y1009450D03*
X948799Y1047950D03*
Y1028950D03*
X949799Y1068950D03*
Y1080950D03*
X950699Y1107750D03*
Y1122250D03*
Y1139750D03*
X950199Y1159250D03*
Y1178250D03*
X950699Y1262750D03*
Y1281750D03*
X943799Y1342950D03*
Y1380850D03*
X944000Y1391900D03*
X946700Y1426500D03*
X944000Y1511300D03*
X943199Y1531650D03*
X933199Y1577550D03*
X944499Y1632650D03*
X940499Y1656950D03*
X941499Y1679550D03*
X931499Y1702050D03*
X949799Y1756250D03*
X941800Y1787700D03*
X941499Y1776250D03*
X934200Y1793500D03*
X932199Y1801850D03*
X937199Y1869950D03*
X937499Y1893850D03*
X938199Y1917150D03*
X947499Y1936050D03*
X930999Y1931050D03*
X945199Y1946350D03*
X930999Y1950050D03*
X946199Y1966650D03*
X931499Y1962050D03*
X930199Y1979550D03*
X936999Y1986550D03*
X960999Y6550D03*
X954799Y17850D03*
X965999Y47050D03*
Y56050D03*
Y64050D03*
X966499Y73050D03*
Y82050D03*
X958999Y96050D03*
X961499Y100050D03*
X968399Y137150D03*
X967399Y180350D03*
X958799Y167350D03*
X956099Y181350D03*
X952799Y199150D03*
Y213650D03*
Y231150D03*
X952299Y250650D03*
Y269650D03*
X953299Y290650D03*
X952799Y324650D03*
Y310150D03*
Y342150D03*
X952299Y361650D03*
Y380650D03*
X953299Y401650D03*
X954799Y434150D03*
Y419650D03*
Y451650D03*
X966199Y473350D03*
Y492350D03*
X951799Y489650D03*
X967199Y513350D03*
X951799Y504150D03*
Y521650D03*
X966499Y552050D03*
X951299Y560150D03*
Y541150D03*
X966799Y566350D03*
X952299Y581150D03*
X966799Y585350D03*
X967799Y606350D03*
X969499Y639050D03*
Y653550D03*
Y671050D03*
X968999Y709550D03*
Y690550D03*
X969999Y730550D03*
Y744250D03*
Y758750D03*
Y776250D03*
X969499Y795750D03*
Y814750D03*
X970499Y835750D03*
Y847750D03*
Y862250D03*
X969999Y899250D03*
X970499Y879750D03*
X969999Y918250D03*
X970999Y939250D03*
X965999Y954550D03*
X971999Y996550D03*
Y1011050D03*
Y1028550D03*
X971499Y1067050D03*
Y1048050D03*
X951199Y1211250D03*
Y1199250D03*
Y1225750D03*
Y1243250D03*
X951699Y1302750D03*
X965099Y1324350D03*
X952499Y1361850D03*
X964400Y1409700D03*
X966600Y1529100D03*
X961400Y1528700D03*
X961900Y1522400D03*
X967100Y1522800D03*
X962100Y1516000D03*
X967300Y1516400D03*
X961600Y1534400D03*
X972000Y1547500D03*
X966100D03*
X960900Y1547100D03*
X961400Y1540800D03*
X966600Y1541200D03*
X966800Y1534800D03*
X961600Y1552900D03*
X966800Y1553300D03*
X972000Y1566000D03*
X966100D03*
X960900Y1565600D03*
X961400Y1559300D03*
X966600Y1559700D03*
X961900Y1572400D03*
X967100Y1572800D03*
X966400Y1585500D03*
X961200Y1585100D03*
X961700Y1578800D03*
X966900Y1579200D03*
X966500Y1592000D03*
X961300Y1591600D03*
X966300Y1598400D03*
X961100Y1598000D03*
X960600Y1604300D03*
X971700Y1604700D03*
X965800D03*
X957799Y1646950D03*
X955499Y1690850D03*
X958799Y1715750D03*
X965349Y1742000D03*
X954499Y1783550D03*
X971000Y1803000D03*
X971500Y1871500D03*
X966799Y1892150D03*
X955499Y1893050D03*
Y1902050D03*
X954099Y1915450D03*
X955799Y1951950D03*
X971499Y1956050D03*
Y1937050D03*
X953799Y1977950D03*
X971499Y1965050D03*
X956499Y1986050D03*
X976499Y6550D03*
X974699Y21450D03*
X991399Y22450D03*
X977399Y44050D03*
X974699Y64650D03*
X991999Y56050D03*
X983099Y83650D03*
X977699Y109150D03*
X981099Y123450D03*
X988699Y174350D03*
X982999Y189050D03*
Y203550D03*
Y221050D03*
X982499Y240550D03*
Y259550D03*
X983499Y280550D03*
X983999Y301550D03*
Y316050D03*
Y333550D03*
X983499Y353050D03*
Y372050D03*
X983999Y412550D03*
X984499Y393050D03*
X983999Y427050D03*
Y444550D03*
X983499Y464050D03*
Y483050D03*
X984499Y504050D03*
X985999Y536550D03*
Y522050D03*
Y554050D03*
X985499Y573550D03*
Y592550D03*
X986499Y613550D03*
X992999Y894550D03*
Y913550D03*
X972499Y1088050D03*
X975999Y1101050D03*
Y1115550D03*
X975499Y1152550D03*
X975999Y1133050D03*
X975499Y1171550D03*
X976499Y1192550D03*
Y1204550D03*
Y1219050D03*
Y1236550D03*
X975999Y1256050D03*
Y1275050D03*
X976999Y1296050D03*
X975100Y1342600D03*
X976499Y1362550D03*
Y1377050D03*
X992500Y1397300D03*
X973200Y1516400D03*
X972500Y1529100D03*
X973000Y1522800D03*
X972700Y1534800D03*
X972500Y1541200D03*
X972700Y1553300D03*
X972500Y1559700D03*
X973000Y1572800D03*
X972300Y1585500D03*
X972800Y1579200D03*
X972400Y1592000D03*
X972200Y1598400D03*
X981200Y1618002D03*
X990425Y1633898D03*
X987029Y1634075D03*
X989502Y1646000D03*
X988800Y1658300D03*
X989000Y1663802D03*
X987200Y1675600D03*
X989900Y1678800D03*
X989999Y1718050D03*
X993299Y1734350D03*
X976600Y1757100D03*
X976399Y1772250D03*
Y1791150D03*
X974699Y1914450D03*
X991999Y1915750D03*
X992299Y1929050D03*
X980999Y1933350D03*
X987999Y1949050D03*
Y1971950D03*
X989999Y1962650D03*
X973999Y1986550D03*
X995999Y6050D03*
X1013499Y6550D03*
X1002699Y40050D03*
X1005299Y71350D03*
X994399Y101250D03*
X1010599Y115550D03*
X1005299Y179950D03*
Y194450D03*
Y211950D03*
X1004799Y231450D03*
Y250450D03*
X1005799Y271450D03*
X1005299Y305450D03*
Y290950D03*
Y322950D03*
X1004799Y342450D03*
Y361450D03*
X1005799Y382450D03*
X1007299Y400450D03*
Y432450D03*
Y414950D03*
X1000699Y463350D03*
Y482350D03*
X1001699Y503350D03*
X1003999Y526850D03*
X1003499Y546350D03*
Y565350D03*
X1004499Y586350D03*
X1005999Y618850D03*
Y604350D03*
Y636350D03*
X994999Y747550D03*
Y733050D03*
Y765050D03*
X994499Y784550D03*
Y803550D03*
X995499Y824550D03*
X993499Y857550D03*
Y843050D03*
Y875050D03*
X994499Y941550D03*
X993999Y934550D03*
X994499Y956050D03*
Y973550D03*
X993999Y993050D03*
Y1012050D03*
X994999Y1033050D03*
Y1045050D03*
X998599Y1110950D03*
Y1096450D03*
Y1128450D03*
X998099Y1147950D03*
Y1166950D03*
X999099Y1187950D03*
Y1214450D03*
Y1199950D03*
Y1231950D03*
X998599Y1251450D03*
Y1270450D03*
X999599Y1291450D03*
X996500Y1324800D03*
X1000700Y1358100D03*
X994200Y1421500D03*
X1008999Y1702450D03*
X1008599Y1716050D03*
X994999Y1748950D03*
X999999Y1775250D03*
X1009999Y1797450D03*
X993499Y1805550D03*
X1007599Y1818450D03*
X993499Y1824550D03*
X1003599Y1846650D03*
X993499Y1833550D03*
X1011299Y1860650D03*
X995699Y1858950D03*
X1001599Y1921450D03*
X1000999Y1946350D03*
X1002500Y1953500D03*
X1005000Y1980500D03*
X1022000Y15500D03*
X1016499Y1301050D03*
X1022599Y1322950D03*
X1023300Y1344400D03*
X1024300Y1365200D03*
Y1393600D03*
X1022299Y1715750D03*
X1016899Y1731650D03*
X1020299Y1746650D03*
X1015299Y1765950D03*
X1026899Y1768550D03*
G54D18*
X78150Y28858D03*
Y178464D03*
Y434370D03*
Y583976D03*
Y839882D03*
Y989488D03*
Y1245394D03*
Y1395000D03*
Y1650906D03*
Y1800512D03*
X158071Y191614D03*
Y341220D03*
Y597126D03*
Y746732D03*
Y1002638D03*
Y1152244D03*
Y1408150D03*
Y1557756D03*
Y1813662D03*
Y1963268D03*
X886417Y191614D03*
Y341220D03*
Y597126D03*
Y746732D03*
Y1002638D03*
Y1152244D03*
Y1408150D03*
Y1557756D03*
Y1813662D03*
Y1963268D03*
G54D10*
X-38436Y23633D03*
X-36811Y1104775D03*
X-35919Y1969497D03*
X1072493Y21507D03*
X1075940Y1769358D03*
G54D17*
X68898Y17047D03*
Y190275D03*
Y422559D03*
Y595787D03*
Y828071D03*
Y1001299D03*
Y1233583D03*
Y1406811D03*
Y1639095D03*
Y1812323D03*
G54D14*
X9843Y353144D03*
Y717711D03*
Y762617D03*
Y875216D03*
Y1337396D03*
Y1701963D03*
Y1746869D03*
Y1859468D03*
G54D23*
X1019291Y1416024D03*
Y1694212D03*
G54D12*
X10000Y16500D03*
X11999Y53550D03*
X11499Y34050D03*
X11999Y69050D03*
Y88550D03*
X11499Y106050D03*
X11999Y124550D03*
X11499Y142050D03*
X11999Y177050D03*
Y161550D03*
Y196550D03*
X11499Y214050D03*
X9499Y229050D03*
X8999Y246550D03*
X9499Y281550D03*
Y266050D03*
Y301050D03*
X8999Y318550D03*
Y889550D03*
X8499Y907050D03*
X8999Y942050D03*
Y926550D03*
Y961550D03*
X8499Y979050D03*
X8999Y988550D03*
Y1025550D03*
X8499Y1006050D03*
X8999Y1041050D03*
Y1060550D03*
X8499Y1089050D03*
Y1078050D03*
X7999Y1106550D03*
X8499Y1126050D03*
Y1141550D03*
Y1161050D03*
X7999Y1192550D03*
Y1178550D03*
X7499Y1210050D03*
X7999Y1229550D03*
Y1245050D03*
Y1264550D03*
X7499Y1282050D03*
X8299Y1320050D03*
X8799Y1302550D03*
X21499Y1073250D03*
X21399Y1090850D03*
X21299Y1300250D03*
X21799Y1282750D03*
X821499Y314050D03*
X838999Y313550D03*
X863999D03*
X855350Y1703201D03*
X879200Y1698700D03*
X879900Y1709300D03*
X883900Y1709500D03*
X875900D03*
X872950Y1744401D03*
X893200Y1721300D03*
Y1730000D03*
X994999Y1986550D03*
X1020499Y50550D03*
X1020999Y33050D03*
Y70050D03*
Y85550D03*
Y105050D03*
X1020499Y122550D03*
X1020999Y158550D03*
X1021499Y141050D03*
Y178050D03*
Y193550D03*
Y213050D03*
X1020999Y230550D03*
Y252050D03*
X1020499Y269550D03*
X1020999Y304550D03*
Y289050D03*
Y324050D03*
X1020499Y341550D03*
Y391550D03*
X1020999Y374050D03*
Y411050D03*
Y426550D03*
Y446050D03*
X1020499Y463550D03*
X1021999Y486550D03*
X1021499Y504050D03*
X1021999Y539050D03*
Y523550D03*
Y558550D03*
X1021499Y576050D03*
X1020499Y623050D03*
X1020999Y605550D03*
Y642550D03*
Y658050D03*
Y677550D03*
X1020499Y695050D03*
X1020999Y720050D03*
X1020499Y737550D03*
X1020999Y772550D03*
Y757050D03*
Y792050D03*
X1020499Y809550D03*
Y828050D03*
X1019999Y845550D03*
X1020499Y865050D03*
Y880550D03*
X1019999Y917550D03*
X1020499Y900050D03*
X1019999Y934050D03*
X1019499Y951550D03*
X1019999Y971050D03*
Y986550D03*
X1019499Y1023550D03*
X1019999Y1006050D03*
Y1043050D03*
Y1058550D03*
X1020499Y1081550D03*
X1019999Y1099050D03*
X1020499Y1118550D03*
Y1134050D03*
X1019499Y1146050D03*
X1018999Y1163550D03*
X1019499Y1183050D03*
Y1198550D03*
X1016999Y1219050D03*
X1016499Y1236550D03*
X1016999Y1256050D03*
Y1271550D03*
X1022999Y1784550D03*
X1022499Y1802050D03*
X1022999Y1821550D03*
Y1837050D03*
X1020999Y1860050D03*
X1020499Y1877550D03*
X1020999Y1912550D03*
Y1897050D03*
X1017499Y1954550D03*
X1017999Y1937050D03*
X1023000Y1973000D03*
X1017999Y1987050D03*
G54D20*
X117499Y1745050D03*
X123499Y1747050D03*
X144499Y1745550D03*
X137999Y1747723D03*
X129999Y1747050D03*
G54D13*
X29531Y309549D03*
Y1029510D03*
X17720Y1903132D03*
X271657Y267699D03*
Y673210D03*
Y1078722D03*
Y1484234D03*
Y1889746D03*
X994098Y149588D03*
Y673210D03*
Y1068880D03*
%LPC*%
G75*
G54D24*
G01X-87137Y-139897D02*
Y-107897D01*
G01X-75137Y-123897D02*
G02I-12000J0D01*
G01X-80287D02*
G02I-6850J0D01*
G01X-71137D02*
X-103137D01*
G01X-71137Y-139897D02*
Y-219897D01*
G01D02*
X1129963D01*
G01X-71137Y-175397D02*
X1129963D01*
G01X-71137Y-139897D02*
X1129963D01*
G01X342463D02*
Y-219897D01*
G01X479963Y-139897D02*
Y-219897D01*
G01X594963Y-139897D02*
Y-219897D01*
G01X762463Y-139897D02*
Y-219897D01*
G01X932463Y-139897D02*
Y-219897D01*
G01X1129963Y-139897D02*
Y-219897D01*
G01X1157963Y-123897D02*
G02I-12000J0D01*
G01X1152813D02*
G02I-6850J0D01*
G01X1161963D02*
X1129963D01*
G01X1145963Y-139897D02*
Y-107897D01*
G54D25*
G01X-53190Y-209897D02*
Y-192397D01*
G01X-44894D02*
X-53190Y-203189D01*
G01X-43584Y-209897D02*
X-49479Y-198231D01*
G01X-35909Y-209897D02*
Y-192397D01*
X-25865Y-209897D01*
Y-192397D01*
G01X-13387Y-209897D02*
X-15134Y-209605D01*
X-16662Y-208439D01*
X-17972Y-206689D01*
X-18846Y-204647D01*
X-19282Y-202314D01*
Y-199980D01*
X-18846Y-197647D01*
X-17972Y-195605D01*
X-16662Y-193856D01*
X-15134Y-192689D01*
X-13387Y-192397D01*
X-11641Y-192689D01*
X-10112Y-193856D01*
X-8802Y-195605D01*
X-7928Y-197647D01*
X-7492Y-199980D01*
Y-202314D01*
X-7928Y-204647D01*
X-8802Y-206689D01*
X-10112Y-208439D01*
X-11641Y-209605D01*
X-13387Y-209897D01*
G01X-472D02*
X8698Y-192397D01*
G01X-472D02*
X8698Y-209897D01*
G01X34310D02*
Y-192397D01*
X38676D01*
X40423Y-193272D01*
X41733Y-194439D01*
X42825Y-196188D01*
X43698Y-198231D01*
X43916Y-201147D01*
X43698Y-204064D01*
X42825Y-206106D01*
X41733Y-207856D01*
X40423Y-209022D01*
X38676Y-209897D01*
X34310D01*
G01X52246D02*
Y-192397D01*
X57705D01*
X59451Y-193272D01*
X60543Y-194439D01*
X60980Y-196772D01*
X60543Y-199106D01*
X59233Y-200564D01*
X57705Y-201439D01*
X52246D01*
G01X57705D02*
X60980Y-209897D01*
G01X71493Y-192397D02*
X76733D01*
G01X74113D02*
Y-209897D01*
G01X71493D02*
X76733D01*
G01X86154Y-192397D02*
X91613Y-209897D01*
X97072Y-192397D01*
G01X113480Y-209897D02*
X104746D01*
Y-192397D01*
X113480D01*
G01X109986Y-200855D02*
X104746D01*
G01X139746Y-209897D02*
Y-192397D01*
X144986D01*
X146733Y-193272D01*
X148043Y-195314D01*
X148480Y-197647D01*
X148043Y-199980D01*
X146951Y-201730D01*
X144986Y-202606D01*
X139746D01*
G01X157246Y-192397D02*
Y-209897D01*
X165980D01*
G01X173654D02*
X179113Y-192397D01*
X184572Y-209897D01*
G01X182606Y-203772D02*
X175619D01*
G01X191591Y-209897D02*
Y-192397D01*
X201635Y-209897D01*
Y-192397D01*
G01X218480Y-209897D02*
X209746D01*
Y-192397D01*
X218480D01*
G01X214986Y-200855D02*
X209746D01*
G01X250859Y-200564D02*
X251733Y-199689D01*
X252388Y-198231D01*
X252825Y-196188D01*
X252388Y-194439D01*
X251515Y-193272D01*
X249986Y-192397D01*
X244091D01*
Y-209897D01*
X251296D01*
X252825Y-208731D01*
X253698Y-206980D01*
X254135Y-204939D01*
X253698Y-202897D01*
X252388Y-201147D01*
X250859Y-200564D01*
X244091D01*
G01X266613Y-209897D02*
X264866Y-209605D01*
X263338Y-208439D01*
X262028Y-206689D01*
X261154Y-204647D01*
X260718Y-202314D01*
Y-199980D01*
X261154Y-197647D01*
X262028Y-195605D01*
X263338Y-193856D01*
X264866Y-192689D01*
X266613Y-192397D01*
X268359Y-192689D01*
X269888Y-193856D01*
X271198Y-195605D01*
X272072Y-197647D01*
X272508Y-199980D01*
Y-202314D01*
X272072Y-204647D01*
X271198Y-206689D01*
X269888Y-208439D01*
X268359Y-209605D01*
X266613Y-209897D01*
G01X278654D02*
X284113Y-192397D01*
X289572Y-209897D01*
G01X287606Y-203772D02*
X280619D01*
G01X297246Y-209897D02*
Y-192397D01*
X302705D01*
X304451Y-193272D01*
X305543Y-194439D01*
X305980Y-196772D01*
X305543Y-199106D01*
X304233Y-200564D01*
X302705Y-201439D01*
X297246D01*
G01X302705D02*
X305980Y-209897D01*
G01X314310D02*
Y-192397D01*
X318676D01*
X320423Y-193272D01*
X321733Y-194439D01*
X322825Y-196188D01*
X323698Y-198231D01*
X323916Y-201147D01*
X323698Y-204064D01*
X322825Y-206106D01*
X321733Y-207856D01*
X320423Y-209022D01*
X318676Y-209897D01*
X314310D01*
G01X94686Y-164897D02*
Y-147397D01*
X100363Y-161980D01*
X106040Y-147397D01*
Y-164897D01*
G01X117863D02*
X116553Y-164605D01*
X115243Y-163439D01*
X114369Y-161397D01*
X113933Y-159064D01*
X114369Y-156730D01*
X115243Y-154689D01*
X116553Y-153522D01*
X117863Y-153231D01*
X119173Y-153522D01*
X120483Y-154689D01*
X121356Y-156730D01*
X121575Y-159064D01*
X121356Y-161397D01*
X120483Y-163439D01*
X119173Y-164605D01*
X117863Y-164897D01*
G01X139293Y-147397D02*
Y-164897D01*
G01Y-162273D02*
X138420Y-163731D01*
X137109Y-164605D01*
X135581Y-164897D01*
X133835Y-164314D01*
X132525Y-162856D01*
X131651Y-161106D01*
X131433Y-159064D01*
X131651Y-157022D01*
X132525Y-155272D01*
X133835Y-153814D01*
X135581Y-153231D01*
X137109Y-153522D01*
X138201Y-154106D01*
X139293Y-155272D01*
G01X149588Y-157022D02*
X156575D01*
X155920Y-154980D01*
X154828Y-153814D01*
X153300Y-153231D01*
X151771Y-153522D01*
X150461Y-154397D01*
X149588Y-156439D01*
X149151Y-158189D01*
Y-159939D01*
X149588Y-161689D01*
X150680Y-163439D01*
X151990Y-164605D01*
X153518Y-164897D01*
X155046Y-164314D01*
X156575Y-162564D01*
G01X170363Y-164897D02*
Y-147397D01*
G01X376163Y-209897D02*
Y-192397D01*
X373543Y-195897D01*
G01Y-209897D02*
X378783D01*
G01X389515Y-195314D02*
X390825Y-193564D01*
X392353Y-192689D01*
X394100Y-192397D01*
X396283Y-192980D01*
X397811Y-194439D01*
X398248Y-196188D01*
X398030Y-197939D01*
X397156Y-199397D01*
X392790Y-202314D01*
X390825Y-204355D01*
X389515Y-207273D01*
X389078Y-209897D01*
X398248D01*
G01X413783D02*
Y-192397D01*
X405704Y-204939D01*
X416622D01*
G01X423860Y-206397D02*
X425169Y-208439D01*
X426916Y-209605D01*
X428881Y-209897D01*
X430628Y-209605D01*
X432375Y-208147D01*
X433466Y-206397D01*
X433685Y-204647D01*
X433248Y-202606D01*
X431720Y-201147D01*
X430191Y-200564D01*
X428226D01*
G01X430191D02*
X431501Y-199689D01*
X432593Y-198231D01*
X433030Y-196481D01*
X432593Y-194730D01*
X431501Y-193272D01*
X429536Y-192397D01*
X427571Y-192689D01*
X425606Y-193856D01*
G01X442015Y-195314D02*
X443325Y-193564D01*
X444853Y-192689D01*
X446600Y-192397D01*
X448783Y-192980D01*
X450311Y-194439D01*
X450748Y-196188D01*
X450530Y-197939D01*
X449656Y-199397D01*
X445290Y-202314D01*
X443325Y-204355D01*
X442015Y-207273D01*
X441578Y-209897D01*
X450748D01*
G01X363046Y-164897D02*
Y-147397D01*
X368286D01*
X370033Y-148272D01*
X371343Y-150314D01*
X371780Y-152647D01*
X371343Y-154980D01*
X370251Y-156730D01*
X368286Y-157606D01*
X363046D01*
G01X389716Y-148856D02*
X388406Y-147980D01*
X386878Y-147397D01*
X385131D01*
X383166Y-148272D01*
X381638Y-149730D01*
X380546Y-151481D01*
X379673Y-154397D01*
X379454Y-157022D01*
X379891Y-159647D01*
X380546Y-161397D01*
X381856Y-163147D01*
X383385Y-164314D01*
X384913Y-164897D01*
X386441D01*
X387970Y-164314D01*
X389280Y-163439D01*
X390372Y-162273D01*
G01X404159Y-155564D02*
X405033Y-154689D01*
X405688Y-153231D01*
X406125Y-151188D01*
X405688Y-149439D01*
X404815Y-148272D01*
X403286Y-147397D01*
X397391D01*
Y-164897D01*
X404596D01*
X406125Y-163731D01*
X406998Y-161980D01*
X407435Y-159939D01*
X406998Y-157897D01*
X405688Y-156147D01*
X404159Y-155564D01*
X397391D01*
G01X413363Y-170730D02*
X426463D01*
G01X432391Y-164897D02*
Y-147397D01*
X442435Y-164897D01*
Y-147397D01*
G01X454913Y-164897D02*
X453166Y-164605D01*
X451638Y-163439D01*
X450328Y-161689D01*
X449454Y-159647D01*
X449018Y-157314D01*
Y-154980D01*
X449454Y-152647D01*
X450328Y-150605D01*
X451638Y-148856D01*
X453166Y-147689D01*
X454913Y-147397D01*
X456659Y-147689D01*
X458188Y-148856D01*
X459498Y-150605D01*
X460372Y-152647D01*
X460808Y-154980D01*
Y-157314D01*
X460372Y-159647D01*
X459498Y-161689D01*
X458188Y-163439D01*
X456659Y-164605D01*
X454913Y-164897D01*
G01X505754Y-147397D02*
X511213Y-164897D01*
X516672Y-147397D01*
G01X533080Y-164897D02*
X524346D01*
Y-147397D01*
X533080D01*
G01X529586Y-155855D02*
X524346D01*
G01X541846Y-164897D02*
Y-147397D01*
X547305D01*
X549051Y-148272D01*
X550143Y-149439D01*
X550580Y-151772D01*
X550143Y-154106D01*
X548833Y-155564D01*
X547305Y-156439D01*
X541846D01*
G01X547305D02*
X550580Y-164897D01*
G01X563713Y-165480D02*
X563276Y-165189D01*
Y-164605D01*
X563713Y-164314D01*
X564150Y-164605D01*
Y-165189D01*
X563713Y-165480D01*
G01X537463Y-209897D02*
Y-192397D01*
X534843Y-195897D01*
G01Y-209897D02*
X540083D01*
G01X630546Y-147397D02*
Y-164897D01*
X639280D01*
G01X656343D02*
Y-153231D01*
G01Y-155272D02*
X655470Y-154106D01*
X654159Y-153522D01*
X652631Y-153231D01*
X651103Y-153814D01*
X649793Y-154980D01*
X648919Y-156730D01*
X648483Y-159064D01*
X648919Y-161397D01*
X649793Y-163147D01*
X651103Y-164314D01*
X652631Y-164897D01*
X654159Y-164605D01*
X655470Y-163731D01*
X656343Y-162564D01*
G01X665328Y-170147D02*
X666638Y-170730D01*
X668385Y-170147D01*
X669476Y-168981D01*
X670350Y-167522D01*
X671659Y-162856D01*
X674498Y-153231D01*
G01X667511D02*
X671659Y-162856D01*
G01X684138Y-157022D02*
X691125D01*
X690470Y-154980D01*
X689378Y-153814D01*
X687850Y-153231D01*
X686321Y-153522D01*
X685011Y-154397D01*
X684138Y-156439D01*
X683701Y-158189D01*
Y-159939D01*
X684138Y-161689D01*
X685230Y-163439D01*
X686540Y-164605D01*
X688068Y-164897D01*
X689596Y-164314D01*
X691125Y-162564D01*
G01X701856Y-164897D02*
Y-153231D01*
G01Y-155564D02*
X702948Y-154397D01*
X704040Y-153522D01*
X705568Y-153231D01*
X706659Y-153522D01*
X707970Y-154397D01*
G01X719138Y-162856D02*
X720230Y-164022D01*
X721758Y-164897D01*
X723068D01*
X724378Y-164314D01*
X725251Y-163439D01*
X725688Y-162273D01*
X725470Y-160522D01*
X724596Y-159647D01*
X720666Y-157897D01*
X719793Y-155855D01*
X720230Y-154397D01*
X721103Y-153522D01*
X722413Y-153231D01*
X723723Y-153522D01*
X725033Y-154397D01*
G01X718030Y-192397D02*
Y-209897D01*
X709296D01*
G01X696600D02*
X696163Y-206106D01*
X695508Y-202897D01*
X694635Y-199980D01*
X693543Y-196772D01*
X691796Y-192397D01*
X700530D01*
G01X677353Y-201147D02*
X672986D01*
Y-206397D01*
X674296Y-208147D01*
X675825Y-209314D01*
X678008Y-209897D01*
X680191Y-209314D01*
X681720Y-208147D01*
X683030Y-206397D01*
X683903Y-204355D01*
X684340Y-202022D01*
Y-199980D01*
X683903Y-198231D01*
X683030Y-196188D01*
X681720Y-194439D01*
X680410Y-193272D01*
X678663Y-192397D01*
X677135D01*
X675388Y-192980D01*
X674078Y-194147D01*
G01X666185Y-209897D02*
Y-192397D01*
X656141Y-209897D01*
Y-192397D01*
G01X648466Y-209897D02*
Y-192397D01*
X644100D01*
X642353Y-193272D01*
X641043Y-194439D01*
X639951Y-196188D01*
X639078Y-198231D01*
X638860Y-201147D01*
X639078Y-204064D01*
X639951Y-206106D01*
X641043Y-207856D01*
X642353Y-209022D01*
X644100Y-209897D01*
X648466D01*
G01X781410Y-164897D02*
Y-147397D01*
X785776D01*
X787523Y-148272D01*
X788833Y-149439D01*
X789925Y-151188D01*
X790798Y-153231D01*
X791016Y-156147D01*
X790798Y-159064D01*
X789925Y-161106D01*
X788833Y-162856D01*
X787523Y-164022D01*
X785776Y-164897D01*
X781410D01*
G01X800438Y-157022D02*
X807425D01*
X806770Y-154980D01*
X805678Y-153814D01*
X804150Y-153231D01*
X802621Y-153522D01*
X801311Y-154397D01*
X800438Y-156439D01*
X800001Y-158189D01*
Y-159939D01*
X800438Y-161689D01*
X801530Y-163439D01*
X802840Y-164605D01*
X804368Y-164897D01*
X805896Y-164314D01*
X807425Y-162564D01*
G01X817938Y-162856D02*
X819030Y-164022D01*
X820558Y-164897D01*
X821868D01*
X823178Y-164314D01*
X824051Y-163439D01*
X824488Y-162273D01*
X824270Y-160522D01*
X823396Y-159647D01*
X819466Y-157897D01*
X818593Y-155855D01*
X819030Y-154397D01*
X819903Y-153522D01*
X821213Y-153231D01*
X822523Y-153522D01*
X823833Y-154397D01*
G01X838713Y-153231D02*
Y-164897D01*
G01Y-148564D02*
X838276Y-148272D01*
Y-147689D01*
X838713Y-147397D01*
X839150Y-147689D01*
Y-148272D01*
X838713Y-148564D01*
G01X853156Y-169272D02*
X854685Y-170439D01*
X856431Y-170730D01*
X857959Y-170439D01*
X859270Y-168981D01*
X860143Y-166939D01*
Y-153231D01*
G01Y-155564D02*
X859270Y-154397D01*
X857959Y-153522D01*
X856431Y-153231D01*
X854685Y-153814D01*
X853593Y-154980D01*
X852719Y-157022D01*
X852283Y-159064D01*
X852501Y-160814D01*
X853375Y-162856D01*
X854685Y-164314D01*
X856431Y-164897D01*
X857741Y-164605D01*
X859270Y-163439D01*
X860143Y-162273D01*
G01X870001Y-164897D02*
Y-153231D01*
G01Y-156147D02*
X870875Y-154689D01*
X872185Y-153522D01*
X873931Y-153231D01*
X875459Y-153522D01*
X876770Y-154689D01*
X877425Y-156730D01*
Y-164897D01*
G01X887938Y-157022D02*
X894925D01*
X894270Y-154980D01*
X893178Y-153814D01*
X891650Y-153231D01*
X890121Y-153522D01*
X888811Y-154397D01*
X887938Y-156439D01*
X887501Y-158189D01*
Y-159939D01*
X887938Y-161689D01*
X889030Y-163439D01*
X890340Y-164605D01*
X891868Y-164897D01*
X893396Y-164314D01*
X894925Y-162564D01*
G01X905656Y-164897D02*
Y-153231D01*
G01Y-155564D02*
X906748Y-154397D01*
X907840Y-153522D01*
X909368Y-153231D01*
X910459Y-153522D01*
X911770Y-154397D01*
G01X825596Y-209897D02*
Y-192397D01*
X831055D01*
X832801Y-193272D01*
X833893Y-194439D01*
X834330Y-196772D01*
X833893Y-199106D01*
X832583Y-200564D01*
X831055Y-201439D01*
X825596D01*
G01X831055D02*
X834330Y-209897D01*
G01X847463D02*
X846153Y-209605D01*
X844843Y-208439D01*
X843969Y-206397D01*
X843533Y-204064D01*
X843969Y-201730D01*
X844843Y-199689D01*
X846153Y-198522D01*
X847463Y-198231D01*
X848773Y-198522D01*
X850083Y-199689D01*
X850956Y-201730D01*
X851175Y-204064D01*
X850956Y-206397D01*
X850083Y-208439D01*
X848773Y-209605D01*
X847463Y-209897D01*
G01X861033D02*
Y-192397D01*
G01Y-201147D02*
X862125Y-199397D01*
X863435Y-198522D01*
X864745Y-198231D01*
X866709Y-198814D01*
X868020Y-199980D01*
X868893Y-202022D01*
Y-204355D01*
X868456Y-206689D01*
X867583Y-208439D01*
X866055Y-209605D01*
X864745Y-209897D01*
X863435Y-209605D01*
X862125Y-208731D01*
X861033Y-207273D01*
G01X952413Y-209897D02*
Y-192397D01*
X949793Y-195897D01*
G01Y-209897D02*
X955033D01*
G01X969913Y-192397D02*
X968166Y-192980D01*
X966856Y-194439D01*
X965983Y-196188D01*
X965328Y-198522D01*
X965110Y-201147D01*
X965328Y-203772D01*
X965983Y-206106D01*
X966856Y-207856D01*
X968166Y-209314D01*
X969913Y-209897D01*
X971659Y-209314D01*
X972970Y-207856D01*
X973843Y-206106D01*
X974498Y-203772D01*
X974716Y-201147D01*
X974498Y-198522D01*
X973843Y-196188D01*
X972970Y-194439D01*
X971659Y-192980D01*
X969913Y-192397D01*
G01X983483Y-210480D02*
X991343Y-192397D01*
G01X1004913Y-209897D02*
Y-192397D01*
X1002293Y-195897D01*
G01Y-209897D02*
X1007533D01*
G01X1018265Y-202606D02*
X1019793Y-200564D01*
X1021103Y-199397D01*
X1022850Y-198814D01*
X1024378Y-199397D01*
X1025470Y-200564D01*
X1026343Y-202314D01*
X1026561Y-204355D01*
X1026343Y-206106D01*
X1025470Y-207856D01*
X1024159Y-209314D01*
X1022631Y-209897D01*
X1020885Y-209314D01*
X1019356Y-207564D01*
X1018483Y-204939D01*
X1018265Y-202022D01*
X1018701Y-198231D01*
X1019356Y-196188D01*
X1020448Y-194147D01*
X1021976Y-192689D01*
X1023505Y-192397D01*
X1025033Y-192980D01*
X1026125Y-194439D01*
G01X1035983Y-210480D02*
X1043843Y-192397D01*
G01X1053265Y-195314D02*
X1054575Y-193564D01*
X1056103Y-192689D01*
X1057850Y-192397D01*
X1060033Y-192980D01*
X1061561Y-194439D01*
X1061998Y-196188D01*
X1061780Y-197939D01*
X1060906Y-199397D01*
X1056540Y-202314D01*
X1054575Y-204355D01*
X1053265Y-207273D01*
X1052828Y-209897D01*
X1061998D01*
G01X1074913Y-192397D02*
X1073166Y-192980D01*
X1071856Y-194439D01*
X1070983Y-196188D01*
X1070328Y-198522D01*
X1070110Y-201147D01*
X1070328Y-203772D01*
X1070983Y-206106D01*
X1071856Y-207856D01*
X1073166Y-209314D01*
X1074913Y-209897D01*
X1076659Y-209314D01*
X1077970Y-207856D01*
X1078843Y-206106D01*
X1079498Y-203772D01*
X1079716Y-201147D01*
X1079498Y-198522D01*
X1078843Y-196188D01*
X1077970Y-194439D01*
X1076659Y-192980D01*
X1074913Y-192397D01*
G01X1092413Y-209897D02*
Y-192397D01*
X1089793Y-195897D01*
G01Y-209897D02*
X1095033D01*
G01X1105765Y-195314D02*
X1107075Y-193564D01*
X1108603Y-192689D01*
X1110350Y-192397D01*
X1112533Y-192980D01*
X1114061Y-194439D01*
X1114498Y-196188D01*
X1114280Y-197939D01*
X1113406Y-199397D01*
X1109040Y-202314D01*
X1107075Y-204355D01*
X1105765Y-207273D01*
X1105328Y-209897D01*
X1114498D01*
G01X1000110Y-164897D02*
Y-147397D01*
X1004476D01*
X1006223Y-148272D01*
X1007533Y-149439D01*
X1008625Y-151188D01*
X1009498Y-153231D01*
X1009716Y-156147D01*
X1009498Y-159064D01*
X1008625Y-161106D01*
X1007533Y-162856D01*
X1006223Y-164022D01*
X1004476Y-164897D01*
X1000110D01*
G01X1026343D02*
Y-153231D01*
G01Y-155272D02*
X1025470Y-154106D01*
X1024159Y-153522D01*
X1022631Y-153231D01*
X1021103Y-153814D01*
X1019793Y-154980D01*
X1018919Y-156730D01*
X1018483Y-159064D01*
X1018919Y-161397D01*
X1019793Y-163147D01*
X1021103Y-164314D01*
X1022631Y-164897D01*
X1024159Y-164605D01*
X1025470Y-163731D01*
X1026343Y-162564D01*
G01X1039913Y-147397D02*
Y-164897D01*
G01X1036856Y-153231D02*
X1042970D01*
G01X1054138Y-157022D02*
X1061125D01*
X1060470Y-154980D01*
X1059378Y-153814D01*
X1057850Y-153231D01*
X1056321Y-153522D01*
X1055011Y-154397D01*
X1054138Y-156439D01*
X1053701Y-158189D01*
Y-159939D01*
X1054138Y-161689D01*
X1055230Y-163439D01*
X1056540Y-164605D01*
X1058068Y-164897D01*
X1059596Y-164314D01*
X1061125Y-162564D01*
M02*
